G04 ================== begin FILE IDENTIFICATION RECORD ==================*
G04 Layout Name:  9052_F0T_PDB_Converter_Brick_F_V03_1208_1600.brd*
G04 Film Name:    panel*
G04 File Format:  Gerber RS274X*
G04 File Origin:  Cadence Allegro 17.2-S081*
G04 Origin Date:  Wed Dec 21 09:54:59 2022*
G04 *
G04 Layer:  DRAWING FORMAT/TITLE_BLOCK_A*
G04 Layer:  MANUFACTURING/PHOTOPLOT_OUTLINE*
G04 Layer:  DRAWING FORMAT/TITLE_BLOCK*
G04 Layer:  DRAWING FORMAT/TITLE_DATA_PANEL*
G04 Layer:  BOARD GEOMETRY/ASSEMBLY_NOTES*
G04 *
G04 Offset:    (0.00 0.00)*
G04 Mirror:    No*
G04 Mode:      Positive*
G04 Rotation:  0*
G04 FullContactRelief:  No*
G04 UndefLineWidth:     6.00*
G04 ================== end FILE IDENTIFICATION RECORD ====================*
%FSLAX25Y25*MOIN*%
%IR0*IPPOS*OFA0.00000B0.00000*MIA0B0*SFA1.00000B1.00000*%
%ADD10C,.1*%
%ADD11C,.006*%
G75*
%LPD*%
G75*
G36*
G01X68898Y-614173D02*
G02I-1969J0D01*
G37*
G36*
G01X1246063Y636929D02*
G02I-1968J0D01*
G37*
G36*
G01X1532883Y-500859D02*
G02I-1969J0D01*
G37*
G54D10*
G01X742500Y-203114D02*
X600500D01*
Y-375114D01*
G01Y-289114D02*
X722500D01*
G01X742500Y383500D02*
X600500D01*
Y211500D01*
G01Y297500D02*
X722500D01*
G54D11*
G01X-297025Y-1013390D02*
Y1828909D01*
X3691357D01*
Y-1013390D01*
X-297025D01*
G01X4093Y-769672D02*
Y-844672D01*
X504093D01*
Y-769672D01*
X4093D01*
G01X0Y-643701D02*
Y-683488D01*
G01X79000Y-633858D02*
X7874D01*
G02X0Y-625984I0J7874D01*
G01D02*
Y-602362D01*
G01Y-566929D02*
G03X19685Y-586614I19685J0D01*
G01X0Y-602362D02*
G02X7874Y-594488I7874J0D01*
G01X0Y-523346D02*
Y-566929D01*
G01X11811Y-511535D02*
G03X0Y-523346I0J-11811D01*
G01Y-450512D02*
G03X11811Y-462323I11811J0D01*
G01X0Y-140827D02*
Y-450512D01*
G01X11811Y-129016D02*
G03X0Y-140827I0J-11811D01*
G01Y-67992D02*
G03X11811Y-79803I11811J0D01*
G01X0Y-27559D02*
Y-67992D01*
G01X19685Y-7874D02*
G03X0Y-27559I0J-19685D01*
G01Y19685D02*
G03X19685Y0I19685J0D01*
G01X0Y63268D02*
Y19685D01*
G01X11811Y75079D02*
G03X0Y63268I0J-11811D01*
G01Y136102D02*
G03X11811Y124291I11811J0D01*
G01X0Y445787D02*
Y136102D01*
G01X11811Y457598D02*
G03X0Y445787I0J-11811D01*
G01Y518622D02*
G03X11811Y506811I11811J0D01*
G01X0Y559055D02*
Y518622D01*
G01X19685Y578740D02*
G03X0Y559055I0J-19685D01*
G01X54252Y586614D02*
X7874D01*
G02X0Y594488I0J7874D01*
G01Y648740D01*
G02X7874Y656614I7874J0D01*
G01X54252D01*
G01X0Y666614D02*
Y706614D01*
G01X587944Y696614D02*
X0D01*
G01X7000Y698114D02*
X0Y696614D01*
X7000Y695114D01*
Y698114D01*
G01X16093Y-834672D02*
Y-839672D01*
G01X14636Y-834672D02*
X17550D01*
G01X22460Y-839672D02*
X19926D01*
Y-834672D01*
X22460D01*
G01X21446Y-837089D02*
X19926D01*
G01X25026Y-834672D02*
Y-839672D01*
X27560D01*
G01X31393Y-839839D02*
X31266Y-839755D01*
Y-839589D01*
X31393Y-839505D01*
X31520Y-839589D01*
Y-839755D01*
X31393Y-839839D01*
G01Y-837589D02*
X31266Y-837505D01*
Y-837339D01*
X31393Y-837255D01*
X31520Y-837339D01*
Y-837505D01*
X31393Y-837589D01*
G01X36176Y-841339D02*
X35543Y-840505D01*
X35226Y-839672D01*
Y-836339D01*
X35543Y-835505D01*
X36176Y-834672D01*
G01X41593D02*
X41086Y-834839D01*
X40706Y-835255D01*
X40453Y-835755D01*
X40263Y-836422D01*
X40200Y-837172D01*
X40263Y-837922D01*
X40453Y-838589D01*
X40706Y-839089D01*
X41086Y-839505D01*
X41593Y-839672D01*
X42100Y-839505D01*
X42480Y-839089D01*
X42733Y-838589D01*
X42923Y-837922D01*
X42986Y-837172D01*
X42923Y-836422D01*
X42733Y-835755D01*
X42480Y-835255D01*
X42100Y-834839D01*
X41593Y-834672D01*
G01X45300Y-838672D02*
X45680Y-839255D01*
X46186Y-839589D01*
X46756Y-839672D01*
X47263Y-839589D01*
X47770Y-839172D01*
X48086Y-838672D01*
X48150Y-838172D01*
X48023Y-837589D01*
X47580Y-837172D01*
X47136Y-837005D01*
X46566D01*
G01X47136D02*
X47516Y-836755D01*
X47833Y-836339D01*
X47960Y-835839D01*
X47833Y-835339D01*
X47516Y-834922D01*
X46946Y-834672D01*
X46376Y-834755D01*
X45806Y-835089D01*
G01X52110Y-841339D02*
X52743Y-840505D01*
X53060Y-839672D01*
Y-836339D01*
X52743Y-835505D01*
X52110Y-834672D01*
G01X55500Y-838672D02*
X55880Y-839255D01*
X56386Y-839589D01*
X56956Y-839672D01*
X57463Y-839589D01*
X57970Y-839172D01*
X58286Y-838672D01*
X58350Y-838172D01*
X58223Y-837589D01*
X57780Y-837172D01*
X57336Y-837005D01*
X56766D01*
G01X57336D02*
X57716Y-836755D01*
X58033Y-836339D01*
X58160Y-835839D01*
X58033Y-835339D01*
X57716Y-834922D01*
X57146Y-834672D01*
X56576Y-834755D01*
X56006Y-835089D01*
G01X60790Y-835505D02*
X61170Y-835005D01*
X61613Y-834755D01*
X62120Y-834672D01*
X62753Y-834839D01*
X63196Y-835255D01*
X63323Y-835755D01*
X63260Y-836255D01*
X63006Y-836672D01*
X61740Y-837505D01*
X61170Y-838089D01*
X60790Y-838922D01*
X60663Y-839672D01*
X63323D01*
G01X66966D02*
X67093Y-838589D01*
X67283Y-837672D01*
X67536Y-836839D01*
X67853Y-835922D01*
X68360Y-834672D01*
X65826D01*
G01X71370Y-838005D02*
X73016D01*
G01X76090Y-835505D02*
X76470Y-835005D01*
X76913Y-834755D01*
X77420Y-834672D01*
X78053Y-834839D01*
X78496Y-835255D01*
X78623Y-835755D01*
X78560Y-836255D01*
X78306Y-836672D01*
X77040Y-837505D01*
X76470Y-838089D01*
X76090Y-838922D01*
X75963Y-839672D01*
X78623D01*
G01X81000Y-838672D02*
X81380Y-839255D01*
X81886Y-839589D01*
X82456Y-839672D01*
X82963Y-839589D01*
X83470Y-839172D01*
X83786Y-838672D01*
X83850Y-838172D01*
X83723Y-837589D01*
X83280Y-837172D01*
X82836Y-837005D01*
X82266D01*
G01X82836D02*
X83216Y-836755D01*
X83533Y-836339D01*
X83660Y-835839D01*
X83533Y-835339D01*
X83216Y-834922D01*
X82646Y-834672D01*
X82076Y-834755D01*
X81506Y-835089D01*
G01X88253Y-839672D02*
Y-834672D01*
X85910Y-838255D01*
X89076D01*
G01X91200Y-838922D02*
X91580Y-839339D01*
X92023Y-839589D01*
X92593Y-839672D01*
X93163Y-839505D01*
X93606Y-839172D01*
X93923Y-838589D01*
X93986Y-837922D01*
X93860Y-837255D01*
X93543Y-836839D01*
X93100Y-836505D01*
X92656Y-836422D01*
X92213Y-836505D01*
X91643Y-836839D01*
X91833Y-834672D01*
X93543D01*
G01X101590Y-839672D02*
Y-834672D01*
X103996D01*
G01X103110Y-837089D02*
X101590D01*
G01X106310Y-839672D02*
X107893Y-834672D01*
X109476Y-839672D01*
G01X108906Y-837922D02*
X106880D01*
G01X111663Y-839672D02*
X114323Y-834672D01*
G01X111663D02*
X114323Y-839672D01*
G01X118093Y-839839D02*
X117966Y-839755D01*
Y-839589D01*
X118093Y-839505D01*
X118220Y-839589D01*
Y-839755D01*
X118093Y-839839D01*
G01Y-837589D02*
X117966Y-837505D01*
Y-837339D01*
X118093Y-837255D01*
X118220Y-837339D01*
Y-837505D01*
X118093Y-837589D01*
G01X122876Y-841339D02*
X122243Y-840505D01*
X121926Y-839672D01*
Y-836339D01*
X122243Y-835505D01*
X122876Y-834672D01*
G01X128293D02*
X127786Y-834839D01*
X127406Y-835255D01*
X127153Y-835755D01*
X126963Y-836422D01*
X126900Y-837172D01*
X126963Y-837922D01*
X127153Y-838589D01*
X127406Y-839089D01*
X127786Y-839505D01*
X128293Y-839672D01*
X128800Y-839505D01*
X129180Y-839089D01*
X129433Y-838589D01*
X129623Y-837922D01*
X129686Y-837172D01*
X129623Y-836422D01*
X129433Y-835755D01*
X129180Y-835255D01*
X128800Y-834839D01*
X128293Y-834672D01*
G01X132000Y-838672D02*
X132380Y-839255D01*
X132886Y-839589D01*
X133456Y-839672D01*
X133963Y-839589D01*
X134470Y-839172D01*
X134786Y-838672D01*
X134850Y-838172D01*
X134723Y-837589D01*
X134280Y-837172D01*
X133836Y-837005D01*
X133266D01*
G01X133836D02*
X134216Y-836755D01*
X134533Y-836339D01*
X134660Y-835839D01*
X134533Y-835339D01*
X134216Y-834922D01*
X133646Y-834672D01*
X133076Y-834755D01*
X132506Y-835089D01*
G01X138810Y-841339D02*
X139443Y-840505D01*
X139760Y-839672D01*
Y-836339D01*
X139443Y-835505D01*
X138810Y-834672D01*
G01X142200Y-838672D02*
X142580Y-839255D01*
X143086Y-839589D01*
X143656Y-839672D01*
X144163Y-839589D01*
X144670Y-839172D01*
X144986Y-838672D01*
X145050Y-838172D01*
X144923Y-837589D01*
X144480Y-837172D01*
X144036Y-837005D01*
X143466D01*
G01X144036D02*
X144416Y-836755D01*
X144733Y-836339D01*
X144860Y-835839D01*
X144733Y-835339D01*
X144416Y-834922D01*
X143846Y-834672D01*
X143276Y-834755D01*
X142706Y-835089D01*
G01X147616Y-839089D02*
X148060Y-839505D01*
X148566Y-839672D01*
X149073Y-839505D01*
X149516Y-839005D01*
X149833Y-838255D01*
X149960Y-837505D01*
Y-836589D01*
X149833Y-835839D01*
X149516Y-835172D01*
X149136Y-834839D01*
X148693Y-834672D01*
X148186Y-834839D01*
X147806Y-835172D01*
X147553Y-835672D01*
X147426Y-836339D01*
X147553Y-836922D01*
X147870Y-837505D01*
X148250Y-837839D01*
X148693Y-837922D01*
X149200Y-837755D01*
X149580Y-837339D01*
X149960Y-836589D01*
G01X153666Y-839672D02*
X153793Y-838589D01*
X153983Y-837672D01*
X154236Y-836839D01*
X154553Y-835922D01*
X155060Y-834672D01*
X152526D01*
G01X158070Y-838005D02*
X159716D01*
G01X162600Y-838672D02*
X162980Y-839255D01*
X163486Y-839589D01*
X164056Y-839672D01*
X164563Y-839589D01*
X165070Y-839172D01*
X165386Y-838672D01*
X165450Y-838172D01*
X165323Y-837589D01*
X164880Y-837172D01*
X164436Y-837005D01*
X163866D01*
G01X164436D02*
X164816Y-836755D01*
X165133Y-836339D01*
X165260Y-835839D01*
X165133Y-835339D01*
X164816Y-834922D01*
X164246Y-834672D01*
X163676Y-834755D01*
X163106Y-835089D01*
G01X167890Y-837589D02*
X168333Y-837005D01*
X168713Y-836672D01*
X169220Y-836505D01*
X169663Y-836672D01*
X169980Y-837005D01*
X170233Y-837505D01*
X170296Y-838089D01*
X170233Y-838589D01*
X169980Y-839089D01*
X169600Y-839505D01*
X169156Y-839672D01*
X168650Y-839505D01*
X168206Y-839005D01*
X167953Y-838255D01*
X167890Y-837422D01*
X168016Y-836339D01*
X168206Y-835755D01*
X168523Y-835172D01*
X168966Y-834755D01*
X169410Y-834672D01*
X169853Y-834839D01*
X170170Y-835255D01*
G01X174193Y-839672D02*
Y-834672D01*
X173433Y-835672D01*
G01Y-839672D02*
X174953D01*
G01X180053D02*
Y-834672D01*
X177710Y-838255D01*
X180876D01*
G01X19685Y-586614D02*
X1271654D01*
G01X29528D02*
G02Y-594488I0J-3937D01*
G01Y-586614D02*
G02Y-594488I0J-3937D01*
G01X7874D02*
X79000D01*
G01X37795Y-511535D02*
X11811D01*
G01Y-462323D02*
X37795D01*
G01Y-129016D02*
X11811D01*
G01Y-79803D02*
X37795D01*
G01X29528Y-7874D02*
G03Y0I0J3937D01*
G01Y-7874D02*
G03Y0I0J3937D01*
G01X19685D02*
X1271654D01*
G01Y-7874D02*
X19685D01*
G01X37795Y75079D02*
X11811D01*
G01Y124291D02*
X37795D01*
G01Y457598D02*
X11811D01*
G01Y506811D02*
X37795D01*
G01X1271654Y578740D02*
X19685D01*
G01X29528D02*
G03Y586614I0J3937D01*
G01Y578740D02*
G03Y586614I0J3937D01*
G01X49213Y-586614D02*
G03Y-594488I0J-3937D01*
G01Y-586614D02*
G03Y-594488I0J-3937D01*
G01X39764Y-509567D02*
G02X37795Y-511535I-1969J0D01*
G01X39764Y-464291D02*
Y-509567D01*
G01X37795Y-462323D02*
G02X39764Y-464291I0J-1969D01*
G01Y-127047D02*
G02X37795Y-129016I-1969J0D01*
G01X39764Y-81771D02*
Y-127047D01*
G01X37795Y-79803D02*
G02X39764Y-81771I0J-1969D01*
G01X49213Y-7874D02*
G02Y0I0J3937D01*
G01Y-7874D02*
G02Y0I0J3937D01*
G01X39764Y122323D02*
Y77047D01*
G01D02*
G02X37795Y75079I-1969J1D01*
G01Y124291D02*
G02X39764Y122323I0J-1969D01*
G01Y504843D02*
Y459567D01*
G01D02*
G02X37795Y457598I-1969J0D01*
G01Y506811D02*
G02X39764Y504843I0J-1968D01*
G01X54252Y656614D02*
X584252D01*
Y586614D01*
X54252D01*
G01Y656614D02*
Y586614D01*
G01X49213Y578740D02*
G02Y586614I0J3937D01*
G01Y578740D02*
G02Y586614I0J3937D01*
G01X1267898Y-633858D02*
X79000D01*
G01X1267898Y-594488D02*
X79000D01*
G01X199093Y-769672D02*
Y-844672D01*
G01Y-819672D02*
X302093D01*
Y-794672D01*
G01X199093D02*
X302093D01*
G01X309600Y-829672D02*
Y-824672D01*
X310866D01*
X311373Y-824922D01*
X311753Y-825255D01*
X312070Y-825755D01*
X312323Y-826339D01*
X312386Y-827172D01*
X312323Y-828005D01*
X312070Y-828589D01*
X311753Y-829089D01*
X311373Y-829422D01*
X310866Y-829672D01*
X309600D01*
G01X314510D02*
X316093Y-824672D01*
X317676Y-829672D01*
G01X317106Y-827922D02*
X315080D01*
G01X321193Y-824672D02*
Y-829672D01*
G01X319736Y-824672D02*
X322650D01*
G01X327560Y-829672D02*
X325026D01*
Y-824672D01*
X327560D01*
G01X326546Y-827089D02*
X325026D01*
G01X331393Y-829839D02*
X331266Y-829755D01*
Y-829589D01*
X331393Y-829505D01*
X331520Y-829589D01*
Y-829755D01*
X331393Y-829839D01*
G01Y-827589D02*
X331266Y-827505D01*
Y-827339D01*
X331393Y-827255D01*
X331520Y-827339D01*
Y-827505D01*
X331393Y-827589D01*
G01X304093Y-769672D02*
Y-844672D01*
G01X302093Y-769672D02*
Y-844672D01*
G01X304093Y-819672D02*
X504093D01*
G01X309726Y-804672D02*
Y-799672D01*
X311246D01*
X311753Y-799922D01*
X312133Y-800505D01*
X312260Y-801172D01*
X312133Y-801839D01*
X311816Y-802339D01*
X311246Y-802589D01*
X309726D01*
G01X314953Y-804839D02*
X317233Y-799672D01*
G01X319736Y-804672D02*
Y-799672D01*
X322650Y-804672D01*
Y-799672D01*
G01X326293Y-804839D02*
X326166Y-804755D01*
Y-804589D01*
X326293Y-804505D01*
X326420Y-804589D01*
Y-804755D01*
X326293Y-804839D01*
G01Y-802589D02*
X326166Y-802505D01*
Y-802339D01*
X326293Y-802255D01*
X326420Y-802339D01*
Y-802505D01*
X326293Y-802589D01*
G01X304093Y-794672D02*
X504093D01*
G01X309726Y-779672D02*
Y-774672D01*
X311246D01*
X311753Y-774922D01*
X312133Y-775505D01*
X312260Y-776172D01*
X312133Y-776839D01*
X311816Y-777339D01*
X311246Y-777589D01*
X309726D01*
G01X314826Y-779672D02*
Y-774672D01*
X316410D01*
X316916Y-774922D01*
X317233Y-775255D01*
X317360Y-775922D01*
X317233Y-776589D01*
X316853Y-777005D01*
X316410Y-777255D01*
X314826D01*
G01X316410D02*
X317360Y-779672D01*
G01X321193D02*
X320686Y-779589D01*
X320243Y-779255D01*
X319863Y-778755D01*
X319610Y-778172D01*
X319483Y-777505D01*
Y-776839D01*
X319610Y-776172D01*
X319863Y-775589D01*
X320243Y-775089D01*
X320686Y-774755D01*
X321193Y-774672D01*
X321700Y-774755D01*
X322143Y-775089D01*
X322523Y-775589D01*
X322776Y-776172D01*
X322903Y-776839D01*
Y-777505D01*
X322776Y-778172D01*
X322523Y-778755D01*
X322143Y-779255D01*
X321700Y-779589D01*
X321193Y-779672D01*
G01X325026Y-778672D02*
X325343Y-779172D01*
X325723Y-779505D01*
X326166Y-779672D01*
X326673Y-779505D01*
X327053Y-779172D01*
X327433Y-778672D01*
X327560Y-778005D01*
Y-774672D01*
G01X332660Y-779672D02*
X330126D01*
Y-774672D01*
X332660D01*
G01X331646Y-777089D02*
X330126D01*
G01X337886Y-775089D02*
X337506Y-774839D01*
X337063Y-774672D01*
X336556D01*
X335986Y-774922D01*
X335543Y-775339D01*
X335226Y-775839D01*
X334973Y-776672D01*
X334910Y-777422D01*
X335036Y-778172D01*
X335226Y-778672D01*
X335606Y-779172D01*
X336050Y-779505D01*
X336493Y-779672D01*
X336936D01*
X337380Y-779505D01*
X337760Y-779255D01*
X338076Y-778922D01*
G01X341593Y-774672D02*
Y-779672D01*
G01X340136Y-774672D02*
X343050D01*
G01X346693Y-779839D02*
X346566Y-779755D01*
Y-779589D01*
X346693Y-779505D01*
X346820Y-779589D01*
Y-779755D01*
X346693Y-779839D01*
G01Y-777589D02*
X346566Y-777505D01*
Y-777339D01*
X346693Y-777255D01*
X346820Y-777339D01*
Y-777505D01*
X346693Y-777589D01*
G01X329095Y-586614D02*
G03Y-594488I0J-3937D01*
G01X309409Y-586614D02*
G02Y-594488I0J-3937D01*
G01Y0D02*
G02Y-7874I0J-3937D01*
G01X329095Y0D02*
G03Y-7874I0J-3937D01*
G01Y586614D02*
G03Y578740I0J-3937D01*
G01X309409Y586614D02*
G02Y578740I0J-3937D01*
G01X419093Y-819672D02*
Y-844672D01*
G01X421726Y-822172D02*
Y-827172D01*
X424260D01*
G01X427333Y-822172D02*
X428853D01*
G01X428093D02*
Y-827172D01*
G01X427333D02*
X428853D01*
G01X433700Y-824505D02*
X433953Y-824255D01*
X434143Y-823839D01*
X434270Y-823255D01*
X434143Y-822755D01*
X433890Y-822422D01*
X433446Y-822172D01*
X431736D01*
Y-827172D01*
X433826D01*
X434270Y-826839D01*
X434523Y-826339D01*
X434650Y-825755D01*
X434523Y-825172D01*
X434143Y-824672D01*
X433700Y-824505D01*
X431736D01*
G01X438293Y-827339D02*
X438166Y-827255D01*
Y-827089D01*
X438293Y-827005D01*
X438420Y-827089D01*
Y-827255D01*
X438293Y-827339D01*
G01Y-825089D02*
X438166Y-825005D01*
Y-824839D01*
X438293Y-824755D01*
X438420Y-824839D01*
Y-825005D01*
X438293Y-825089D01*
G01X470106Y-847839D02*
X470213Y-847714D01*
X470293Y-847505D01*
X470346Y-847214D01*
X470293Y-846964D01*
X470186Y-846797D01*
X470000Y-846672D01*
X469280D01*
Y-849172D01*
X470160D01*
X470346Y-849005D01*
X470453Y-848755D01*
X470506Y-848464D01*
X470453Y-848172D01*
X470293Y-847922D01*
X470106Y-847839D01*
X469280D01*
G01X472573Y-849172D02*
Y-847505D01*
G01Y-847797D02*
X472466Y-847630D01*
X472306Y-847547D01*
X472120Y-847505D01*
X471933Y-847589D01*
X471773Y-847755D01*
X471666Y-848005D01*
X471613Y-848339D01*
X471666Y-848672D01*
X471773Y-848922D01*
X471933Y-849089D01*
X472120Y-849172D01*
X472306Y-849130D01*
X472466Y-849005D01*
X472573Y-848839D01*
G01X473893Y-848880D02*
X474026Y-849047D01*
X474213Y-849172D01*
X474373D01*
X474533Y-849089D01*
X474640Y-848964D01*
X474693Y-848797D01*
X474666Y-848547D01*
X474560Y-848422D01*
X474080Y-848172D01*
X473973Y-847880D01*
X474026Y-847672D01*
X474133Y-847547D01*
X474293Y-847505D01*
X474453Y-847547D01*
X474613Y-847672D01*
G01X476093Y-848047D02*
X476946D01*
X476866Y-847755D01*
X476733Y-847589D01*
X476546Y-847505D01*
X476360Y-847547D01*
X476200Y-847672D01*
X476093Y-847964D01*
X476040Y-848214D01*
Y-848464D01*
X476093Y-848714D01*
X476226Y-848964D01*
X476386Y-849130D01*
X476573Y-849172D01*
X476760Y-849089D01*
X476946Y-848839D01*
G01X478213Y-849172D02*
Y-846672D01*
G01Y-847922D02*
X478346Y-847672D01*
X478506Y-847547D01*
X478666Y-847505D01*
X478906Y-847589D01*
X479066Y-847755D01*
X479173Y-848047D01*
Y-848380D01*
X479120Y-848714D01*
X479013Y-848964D01*
X478826Y-849130D01*
X478666Y-849172D01*
X478506Y-849130D01*
X478346Y-849005D01*
X478213Y-848797D01*
G01X480893Y-849172D02*
X480733Y-849130D01*
X480573Y-848964D01*
X480466Y-848672D01*
X480413Y-848339D01*
X480466Y-848005D01*
X480573Y-847714D01*
X480733Y-847547D01*
X480893Y-847505D01*
X481053Y-847547D01*
X481213Y-847714D01*
X481320Y-848005D01*
X481346Y-848339D01*
X481320Y-848672D01*
X481213Y-848964D01*
X481053Y-849130D01*
X480893Y-849172D01*
G01X483573D02*
Y-847505D01*
G01Y-847797D02*
X483466Y-847630D01*
X483306Y-847547D01*
X483120Y-847505D01*
X482933Y-847589D01*
X482773Y-847755D01*
X482666Y-848005D01*
X482613Y-848339D01*
X482666Y-848672D01*
X482773Y-848922D01*
X482933Y-849089D01*
X483120Y-849172D01*
X483306Y-849130D01*
X483466Y-849005D01*
X483573Y-848839D01*
G01X484920Y-849172D02*
Y-847505D01*
G01Y-847839D02*
X485053Y-847672D01*
X485186Y-847547D01*
X485373Y-847505D01*
X485506Y-847547D01*
X485666Y-847672D01*
G01X487973Y-846672D02*
Y-849172D01*
G01Y-848797D02*
X487866Y-849005D01*
X487706Y-849130D01*
X487520Y-849172D01*
X487306Y-849089D01*
X487146Y-848880D01*
X487040Y-848630D01*
X487013Y-848339D01*
X487040Y-848047D01*
X487146Y-847797D01*
X487306Y-847589D01*
X487520Y-847505D01*
X487706Y-847547D01*
X487840Y-847630D01*
X487973Y-847797D01*
G01X491360Y-849172D02*
Y-846672D01*
X492026D01*
X492240Y-846797D01*
X492373Y-846964D01*
X492426Y-847297D01*
X492373Y-847630D01*
X492213Y-847839D01*
X492026Y-847964D01*
X491360D01*
G01X492026D02*
X492426Y-849172D01*
G01X493693Y-848047D02*
X494546D01*
X494466Y-847755D01*
X494333Y-847589D01*
X494146Y-847505D01*
X493960Y-847547D01*
X493800Y-847672D01*
X493693Y-847964D01*
X493640Y-848214D01*
Y-848464D01*
X493693Y-848714D01*
X493826Y-848964D01*
X493986Y-849130D01*
X494173Y-849172D01*
X494360Y-849089D01*
X494546Y-848839D01*
G01X495813Y-847505D02*
X496293Y-849172D01*
X496773Y-847505D01*
G01X498493Y-849255D02*
X498440Y-849214D01*
Y-849130D01*
X498493Y-849089D01*
X498546Y-849130D01*
Y-849214D01*
X498493Y-849255D01*
G01X500693Y-849172D02*
X500880Y-849130D01*
X501093Y-849005D01*
X501226Y-848797D01*
X501280Y-848505D01*
X501226Y-848214D01*
X501066Y-847964D01*
X500826Y-847839D01*
X500560D01*
X500400Y-847755D01*
X500266Y-847547D01*
X500213Y-847255D01*
X500293Y-846964D01*
X500480Y-846755D01*
X500693Y-846672D01*
X500906Y-846755D01*
X501093Y-846964D01*
X501173Y-847255D01*
X501120Y-847547D01*
X500986Y-847755D01*
X500826Y-847839D01*
X500560D01*
X500320Y-847964D01*
X500160Y-848214D01*
X500106Y-848505D01*
X500160Y-848797D01*
X500293Y-849005D01*
X500506Y-849130D01*
X500693Y-849172D01*
G01X503106Y-847839D02*
X503213Y-847714D01*
X503293Y-847505D01*
X503346Y-847214D01*
X503293Y-846964D01*
X503186Y-846797D01*
X503000Y-846672D01*
X502280D01*
Y-849172D01*
X503160D01*
X503346Y-849005D01*
X503453Y-848755D01*
X503506Y-848464D01*
X503453Y-848172D01*
X503293Y-847922D01*
X503106Y-847839D01*
X502280D01*
G01X465993Y-822172D02*
Y-827172D01*
G01X464536Y-822172D02*
X467450D01*
G01X471093Y-827172D02*
X470713Y-827089D01*
X470333Y-826755D01*
X470080Y-826172D01*
X469953Y-825505D01*
X470080Y-824839D01*
X470333Y-824255D01*
X470713Y-823922D01*
X471093Y-823839D01*
X471473Y-823922D01*
X471853Y-824255D01*
X472106Y-824839D01*
X472170Y-825505D01*
X472106Y-826172D01*
X471853Y-826755D01*
X471473Y-827089D01*
X471093Y-827172D01*
G01X476193D02*
X475813Y-827089D01*
X475433Y-826755D01*
X475180Y-826172D01*
X475053Y-825505D01*
X475180Y-824839D01*
X475433Y-824255D01*
X475813Y-823922D01*
X476193Y-823839D01*
X476573Y-823922D01*
X476953Y-824255D01*
X477206Y-824839D01*
X477270Y-825505D01*
X477206Y-826172D01*
X476953Y-826755D01*
X476573Y-827089D01*
X476193Y-827172D01*
G01X481293D02*
Y-822172D01*
G01X486393Y-827339D02*
X486266Y-827255D01*
Y-827089D01*
X486393Y-827005D01*
X486520Y-827089D01*
Y-827255D01*
X486393Y-827339D01*
G01Y-825089D02*
X486266Y-825005D01*
Y-824839D01*
X486393Y-824755D01*
X486520Y-824839D01*
Y-825005D01*
X486393Y-825089D01*
G01X462093Y-819672D02*
Y-844672D01*
G01Y-794672D02*
Y-819672D01*
G01X464726Y-802172D02*
Y-797172D01*
X466310D01*
X466816Y-797422D01*
X467133Y-797755D01*
X467260Y-798422D01*
X467133Y-799089D01*
X466753Y-799505D01*
X466310Y-799755D01*
X464726D01*
G01X466310D02*
X467260Y-802172D01*
G01X472360D02*
X469826D01*
Y-797172D01*
X472360D01*
G01X471346Y-799589D02*
X469826D01*
G01X474610Y-797172D02*
X476193Y-802172D01*
X477776Y-797172D01*
G01X481293Y-802339D02*
X481166Y-802255D01*
Y-802089D01*
X481293Y-802005D01*
X481420Y-802089D01*
Y-802255D01*
X481293Y-802339D01*
G01Y-800089D02*
X481166Y-800005D01*
Y-799839D01*
X481293Y-799755D01*
X481420Y-799839D01*
Y-800005D01*
X481293Y-800089D01*
G01X519252Y586614D02*
Y656614D01*
G01X552755Y-586614D02*
G02Y-594488I0J-3937D01*
G01Y0D02*
G02Y-7874I0J-3937D01*
G01Y586614D02*
G02Y578740I0J-3937D01*
G01X572441Y-586614D02*
G03Y-594488I0J-3937D01*
G01Y0D02*
G03Y-7874I0J-3937D01*
G01X584252Y656614D02*
G02X592126Y648740I0J-7874D01*
G01Y594488D01*
G02X584252Y586614I-7874J0D01*
G01X572441D02*
G03Y578740I0J-3937D01*
G01X592126Y601929D02*
G02X600000I3937J0D01*
G01X600394Y609803D02*
G03I-1575J0D01*
G01Y617677D02*
G03I-1575J0D01*
G01Y633425D02*
G03I-1575J0D01*
G01Y625551D02*
G03I-1575J0D01*
G01X592126Y641299D02*
G03X600000I3937J0D01*
G01X619685Y-586614D02*
G02Y-594488I0J-3937D01*
G01Y0D02*
G02Y-7874I0J-3937D01*
G01X600000Y648740D02*
G02X607874Y656614I7874J0D01*
G01X1283465D01*
G02X1291339Y648740I0J-7874D01*
G01Y594488D01*
G02X1283465Y586614I-7874J0D01*
G01X607874D01*
G02X600000Y594488I0J7874D01*
G01Y648740D01*
G01X619685Y586614D02*
G02Y578740I0J-3937D01*
G01X600000Y625118D02*
Y648740D01*
G01D02*
G02X607874Y656614I7874J0D01*
G01X649000D01*
G01X624119Y677864D02*
X619469D01*
Y690364D01*
X624119D01*
G01X639371Y-586614D02*
G03Y-594488I0J-3937D01*
G01Y0D02*
G03Y-7874I0J-3937D01*
G01Y586614D02*
G03Y578740I0J-3937D01*
G01X667519Y677864D02*
X672169D01*
Y690364D01*
X667519D01*
G01X703394Y696614D02*
X1291339D01*
G01X796101Y-586614D02*
G02Y-594488I0J-3937D01*
G01Y0D02*
G02Y-7874I0J-3937D01*
G01Y586614D02*
G02Y578740I0J-3937D01*
G01X815787Y-586614D02*
G03Y-594488I0J-3937D01*
G01Y0D02*
G03Y-7874I0J-3937D01*
G01Y586614D02*
G03Y578740I0J-3937D01*
G01X1039447Y-586614D02*
G02Y-594488I0J-3937D01*
G01Y0D02*
G02Y-7874I0J-3937D01*
G01Y586614D02*
G02Y578740I0J-3937D01*
G01X1059133Y-586614D02*
G03Y-594488I0J-3937D01*
G01Y0D02*
G03Y-7874I0J-3937D01*
G01Y586614D02*
G03Y578740I0J-3937D01*
G01X1240339Y-633858D02*
X1283465D01*
G03X1291339Y-625984I0J7874D01*
G01X1242126Y-586614D02*
G02Y-594488I0J-3937D01*
G01Y-586614D02*
G02Y-594488I0J-3937D01*
G01X1283465D02*
X1240339D01*
G01X1242126Y0D02*
G02Y-7874I0J-3937D01*
G01Y0D02*
G02Y-7874I0J-3937D01*
G01Y586614D02*
G02Y578740I0J-3937D01*
G01Y586614D02*
G02Y578740I0J-3937D01*
G01X1271654Y-586614D02*
G03X1291339Y-566929I0J19685D01*
G01X1261811Y-586614D02*
G03Y-594488I0J-3937D01*
G01Y-586614D02*
G03Y-594488I0J-3937D01*
G01Y0D02*
G03Y-7874I0J-3937D01*
G01Y0D02*
G03Y-7874I0J-3937D01*
G01X1271654Y0D02*
G03X1291339Y19685I0J19685D01*
G01Y-27559D02*
G03X1271654Y-7874I-19685J0D01*
G01X1291339Y559055D02*
G03X1271654Y578740I-19685J0D01*
G01X1261811Y586614D02*
G03Y578740I0J-3937D01*
G01Y586614D02*
G03Y578740I0J-3937D01*
G01X1291339Y-643701D02*
Y-729173D01*
G01X1301182Y-633858D02*
X1371418D01*
G01X1291339Y-625984D02*
Y-602362D01*
G01X1301339Y-633858D02*
X1341339D01*
G01X1294329Y-586614D02*
X1330729D01*
G01X1291339Y-602362D02*
G03X1283465Y-594488I-7874J0D01*
G01X1291339Y-566929D02*
Y-27559D01*
G01Y19685D02*
Y559055D01*
G01X1287696Y655381D02*
X1291176Y763637D01*
G01X1285743Y671200D02*
X1287696Y655381D01*
X1290662Y671042D01*
X1285743Y671200D01*
G01X1301339Y656614D02*
X1341339D01*
G01X1291339Y666614D02*
Y706614D01*
G01X1284339Y695114D02*
X1291339Y696614D01*
X1284339Y698114D01*
Y695114D01*
G01X1331339Y-46347D02*
Y-633858D01*
G01X1329839Y-626858D02*
X1331339Y-633858D01*
X1332839Y-626858D01*
X1329839D01*
G01X1350089Y-28772D02*
Y-33422D01*
X1337589D01*
Y-28772D01*
G01X1331339Y69103D02*
Y656614D01*
G01X1350089Y51828D02*
Y56478D01*
X1337589D01*
Y51828D01*
G01X1332839Y649614D02*
X1331339Y656614D01*
X1329839Y649614D01*
X1332839D01*
G01X1503636Y-539530D02*
X1503889Y-539280D01*
X1504079Y-538864D01*
X1504206Y-538280D01*
X1504079Y-537780D01*
X1503826Y-537447D01*
X1503382Y-537197D01*
X1501672D01*
Y-542197D01*
X1503762D01*
X1504206Y-541864D01*
X1504459Y-541364D01*
X1504586Y-540780D01*
X1504459Y-540197D01*
X1504079Y-539697D01*
X1503636Y-539530D01*
X1501672D01*
G01X1507342Y-542197D02*
Y-538864D01*
G01Y-539530D02*
X1507659Y-539197D01*
X1507976Y-538947D01*
X1508419Y-538864D01*
X1508736Y-538947D01*
X1509116Y-539197D01*
G01X1512379Y-539947D02*
X1514406D01*
X1514216Y-539364D01*
X1513899Y-539030D01*
X1513456Y-538864D01*
X1513012Y-538947D01*
X1512632Y-539197D01*
X1512379Y-539780D01*
X1512252Y-540280D01*
Y-540780D01*
X1512379Y-541280D01*
X1512696Y-541780D01*
X1513076Y-542114D01*
X1513519Y-542197D01*
X1513962Y-542030D01*
X1514406Y-541530D01*
G01X1519569Y-542197D02*
Y-538864D01*
G01Y-539447D02*
X1519316Y-539114D01*
X1518936Y-538947D01*
X1518492Y-538864D01*
X1518049Y-539030D01*
X1517669Y-539364D01*
X1517416Y-539864D01*
X1517289Y-540530D01*
X1517416Y-541197D01*
X1517669Y-541697D01*
X1518049Y-542030D01*
X1518492Y-542197D01*
X1518936Y-542114D01*
X1519316Y-541864D01*
X1519569Y-541530D01*
G01X1522452Y-542197D02*
Y-537197D01*
G01X1524479Y-538864D02*
X1522452Y-540780D01*
G01X1523276Y-540030D02*
X1524606Y-542197D01*
G01X1528629Y-537197D02*
Y-542197D01*
G01X1527742Y-538864D02*
X1529516D01*
G01X1534869Y-542197D02*
Y-538864D01*
G01Y-539447D02*
X1534616Y-539114D01*
X1534236Y-538947D01*
X1533792Y-538864D01*
X1533349Y-539030D01*
X1532969Y-539364D01*
X1532716Y-539864D01*
X1532589Y-540530D01*
X1532716Y-541197D01*
X1532969Y-541697D01*
X1533349Y-542030D01*
X1533792Y-542197D01*
X1534236Y-542114D01*
X1534616Y-541864D01*
X1534869Y-541530D01*
G01X1537689Y-542197D02*
Y-537197D01*
G01Y-539697D02*
X1538006Y-539197D01*
X1538386Y-538947D01*
X1538766Y-538864D01*
X1539336Y-539030D01*
X1539716Y-539364D01*
X1539969Y-539947D01*
Y-540614D01*
X1539842Y-541280D01*
X1539589Y-541780D01*
X1539146Y-542114D01*
X1538766Y-542197D01*
X1538386Y-542114D01*
X1538006Y-541864D01*
X1537689Y-541447D01*
G01X1543929Y-542364D02*
X1543802Y-542280D01*
Y-542114D01*
X1543929Y-542030D01*
X1544056Y-542114D01*
Y-542280D01*
X1543929Y-542364D01*
G01Y-540114D02*
X1543802Y-540030D01*
Y-539864D01*
X1543929Y-539780D01*
X1544056Y-539864D01*
Y-540030D01*
X1543929Y-540114D01*
G01X1578426Y-475667D02*
Y-470667D01*
X1580832D01*
G01X1579946Y-473084D02*
X1578426D01*
G01X1584729Y-475667D02*
X1584349Y-475584D01*
X1583969Y-475250D01*
X1583716Y-474667D01*
X1583589Y-474000D01*
X1583716Y-473334D01*
X1583969Y-472750D01*
X1584349Y-472417D01*
X1584729Y-472334D01*
X1585109Y-472417D01*
X1585489Y-472750D01*
X1585742Y-473334D01*
X1585806Y-474000D01*
X1585742Y-474667D01*
X1585489Y-475250D01*
X1585109Y-475584D01*
X1584729Y-475667D01*
G01X1588942D02*
Y-472334D01*
G01Y-473000D02*
X1589259Y-472667D01*
X1589576Y-472417D01*
X1590019Y-472334D01*
X1590336Y-472417D01*
X1590716Y-472667D01*
G01X1598762Y-475667D02*
Y-470667D01*
X1600282D01*
X1600789Y-470917D01*
X1601169Y-471500D01*
X1601296Y-472167D01*
X1601169Y-472834D01*
X1600852Y-473334D01*
X1600282Y-473584D01*
X1598762D01*
G01X1606269Y-475667D02*
Y-472334D01*
G01Y-472917D02*
X1606016Y-472584D01*
X1605636Y-472417D01*
X1605192Y-472334D01*
X1604749Y-472500D01*
X1604369Y-472834D01*
X1604116Y-473334D01*
X1603989Y-474000D01*
X1604116Y-474667D01*
X1604369Y-475167D01*
X1604749Y-475500D01*
X1605192Y-475667D01*
X1605636Y-475584D01*
X1606016Y-475334D01*
X1606269Y-475000D01*
G01X1609152Y-475667D02*
Y-472334D01*
G01Y-473167D02*
X1609406Y-472750D01*
X1609786Y-472417D01*
X1610292Y-472334D01*
X1610736Y-472417D01*
X1611116Y-472750D01*
X1611306Y-473334D01*
Y-475667D01*
G01X1614379Y-473417D02*
X1616406D01*
X1616216Y-472834D01*
X1615899Y-472500D01*
X1615456Y-472334D01*
X1615012Y-472417D01*
X1614632Y-472667D01*
X1614379Y-473250D01*
X1614252Y-473750D01*
Y-474250D01*
X1614379Y-474750D01*
X1614696Y-475250D01*
X1615076Y-475584D01*
X1615519Y-475667D01*
X1615962Y-475500D01*
X1616406Y-475000D01*
G01X1620429Y-475667D02*
Y-470667D01*
G01X1631136Y-473000D02*
X1631389Y-472750D01*
X1631579Y-472334D01*
X1631706Y-471750D01*
X1631579Y-471250D01*
X1631326Y-470917D01*
X1630882Y-470667D01*
X1629172D01*
Y-475667D01*
X1631262D01*
X1631706Y-475334D01*
X1631959Y-474834D01*
X1632086Y-474250D01*
X1631959Y-473667D01*
X1631579Y-473167D01*
X1631136Y-473000D01*
X1629172D01*
G01X1635729Y-475667D02*
X1635349Y-475584D01*
X1634969Y-475250D01*
X1634716Y-474667D01*
X1634589Y-474000D01*
X1634716Y-473334D01*
X1634969Y-472750D01*
X1635349Y-472417D01*
X1635729Y-472334D01*
X1636109Y-472417D01*
X1636489Y-472750D01*
X1636742Y-473334D01*
X1636806Y-474000D01*
X1636742Y-474667D01*
X1636489Y-475250D01*
X1636109Y-475584D01*
X1635729Y-475667D01*
G01X1641969D02*
Y-472334D01*
G01Y-472917D02*
X1641716Y-472584D01*
X1641336Y-472417D01*
X1640892Y-472334D01*
X1640449Y-472500D01*
X1640069Y-472834D01*
X1639816Y-473334D01*
X1639689Y-474000D01*
X1639816Y-474667D01*
X1640069Y-475167D01*
X1640449Y-475500D01*
X1640892Y-475667D01*
X1641336Y-475584D01*
X1641716Y-475334D01*
X1641969Y-475000D01*
G01X1645042Y-475667D02*
Y-472334D01*
G01Y-473000D02*
X1645359Y-472667D01*
X1645676Y-472417D01*
X1646119Y-472334D01*
X1646436Y-472417D01*
X1646816Y-472667D01*
G01X1652169Y-470667D02*
Y-475667D01*
G01Y-474917D02*
X1651916Y-475334D01*
X1651536Y-475584D01*
X1651092Y-475667D01*
X1650586Y-475500D01*
X1650206Y-475084D01*
X1649952Y-474584D01*
X1649889Y-474000D01*
X1649952Y-473417D01*
X1650206Y-472917D01*
X1650586Y-472500D01*
X1651092Y-472334D01*
X1651536Y-472417D01*
X1651852Y-472584D01*
X1652169Y-472917D01*
G01X1579629Y-458067D02*
Y-463067D01*
G01X1578172Y-458067D02*
X1581086D01*
G01X1584729Y-463067D02*
X1584349Y-462984D01*
X1583969Y-462650D01*
X1583716Y-462067D01*
X1583589Y-461400D01*
X1583716Y-460734D01*
X1583969Y-460150D01*
X1584349Y-459817D01*
X1584729Y-459734D01*
X1585109Y-459817D01*
X1585489Y-460150D01*
X1585742Y-460734D01*
X1585806Y-461400D01*
X1585742Y-462067D01*
X1585489Y-462650D01*
X1585109Y-462984D01*
X1584729Y-463067D01*
G01X1588689Y-464734D02*
Y-459734D01*
G01Y-460484D02*
X1589006Y-460067D01*
X1589322Y-459817D01*
X1589829Y-459734D01*
X1590272Y-459817D01*
X1590716Y-460234D01*
X1590906Y-460817D01*
X1590969Y-461400D01*
X1590906Y-461984D01*
X1590716Y-462567D01*
X1590336Y-462900D01*
X1589829Y-463067D01*
X1589386Y-462984D01*
X1588942Y-462734D01*
X1588689Y-462400D01*
G01X1598446Y-463067D02*
X1600029Y-458067D01*
X1601612Y-463067D01*
G01X1601042Y-461317D02*
X1599016D01*
G01X1604052Y-463067D02*
Y-459734D01*
G01Y-460567D02*
X1604306Y-460150D01*
X1604686Y-459817D01*
X1605192Y-459734D01*
X1605636Y-459817D01*
X1606016Y-460150D01*
X1606206Y-460734D01*
Y-463067D01*
G01X1611369Y-458067D02*
Y-463067D01*
G01Y-462317D02*
X1611116Y-462734D01*
X1610736Y-462984D01*
X1610292Y-463067D01*
X1609786Y-462900D01*
X1609406Y-462484D01*
X1609152Y-461984D01*
X1609089Y-461400D01*
X1609152Y-460817D01*
X1609406Y-460317D01*
X1609786Y-459900D01*
X1610292Y-459734D01*
X1610736Y-459817D01*
X1611052Y-459984D01*
X1611369Y-460317D01*
G01X1620936Y-460400D02*
X1621189Y-460150D01*
X1621379Y-459734D01*
X1621506Y-459150D01*
X1621379Y-458650D01*
X1621126Y-458317D01*
X1620682Y-458067D01*
X1618972D01*
Y-463067D01*
X1621062D01*
X1621506Y-462734D01*
X1621759Y-462234D01*
X1621886Y-461650D01*
X1621759Y-461067D01*
X1621379Y-460567D01*
X1620936Y-460400D01*
X1618972D01*
G01X1625529Y-463067D02*
X1625149Y-462984D01*
X1624769Y-462650D01*
X1624516Y-462067D01*
X1624389Y-461400D01*
X1624516Y-460734D01*
X1624769Y-460150D01*
X1625149Y-459817D01*
X1625529Y-459734D01*
X1625909Y-459817D01*
X1626289Y-460150D01*
X1626542Y-460734D01*
X1626606Y-461400D01*
X1626542Y-462067D01*
X1626289Y-462650D01*
X1625909Y-462984D01*
X1625529Y-463067D01*
G01X1630629Y-458067D02*
Y-463067D01*
G01X1629742Y-459734D02*
X1631516D01*
G01X1635729Y-458067D02*
Y-463067D01*
G01X1634842Y-459734D02*
X1636616D01*
G01X1640829Y-463067D02*
X1640449Y-462984D01*
X1640069Y-462650D01*
X1639816Y-462067D01*
X1639689Y-461400D01*
X1639816Y-460734D01*
X1640069Y-460150D01*
X1640449Y-459817D01*
X1640829Y-459734D01*
X1641209Y-459817D01*
X1641589Y-460150D01*
X1641842Y-460734D01*
X1641906Y-461400D01*
X1641842Y-462067D01*
X1641589Y-462650D01*
X1641209Y-462984D01*
X1640829Y-463067D01*
G01X1644029D02*
Y-459734D01*
G01Y-460650D02*
X1644219Y-460234D01*
X1644536Y-459900D01*
X1644979Y-459734D01*
X1645422Y-459900D01*
X1645739Y-460234D01*
X1645929Y-460650D01*
Y-463067D01*
G01Y-460650D02*
X1646119Y-460234D01*
X1646436Y-459900D01*
X1646879Y-459734D01*
X1647322Y-459900D01*
X1647639Y-460234D01*
X1647829Y-460734D01*
Y-463067D01*
G01X1654799Y-462400D02*
X1655306Y-462817D01*
X1655876Y-463067D01*
X1656382D01*
X1656889Y-462817D01*
X1657269Y-462400D01*
X1657459Y-461817D01*
X1657332Y-461234D01*
X1657016Y-460734D01*
X1656446Y-460400D01*
X1655686Y-460234D01*
X1655242Y-459900D01*
X1655052Y-459317D01*
X1655179Y-458734D01*
X1655496Y-458317D01*
X1655939Y-458067D01*
X1656382D01*
X1656826Y-458234D01*
X1657206Y-458650D01*
G01X1661229Y-459734D02*
Y-463067D01*
G01Y-458400D02*
X1661102Y-458317D01*
Y-458150D01*
X1661229Y-458067D01*
X1661356Y-458150D01*
Y-458317D01*
X1661229Y-458400D01*
G01X1667469Y-458067D02*
Y-463067D01*
G01Y-462317D02*
X1667216Y-462734D01*
X1666836Y-462984D01*
X1666392Y-463067D01*
X1665886Y-462900D01*
X1665506Y-462484D01*
X1665252Y-461984D01*
X1665189Y-461400D01*
X1665252Y-460817D01*
X1665506Y-460317D01*
X1665886Y-459900D01*
X1666392Y-459734D01*
X1666836Y-459817D01*
X1667152Y-459984D01*
X1667469Y-460317D01*
G01X1670479Y-460817D02*
X1672506D01*
X1672316Y-460234D01*
X1671999Y-459900D01*
X1671556Y-459734D01*
X1671112Y-459817D01*
X1670732Y-460067D01*
X1670479Y-460650D01*
X1670352Y-461150D01*
Y-461650D01*
X1670479Y-462150D01*
X1670796Y-462650D01*
X1671176Y-462984D01*
X1671619Y-463067D01*
X1672062Y-462900D01*
X1672506Y-462400D01*
G01X1578426Y-475667D02*
Y-470667D01*
X1580832D01*
G01X1579946Y-473084D02*
X1578426D01*
G01X1584729Y-475667D02*
X1584349Y-475584D01*
X1583969Y-475250D01*
X1583716Y-474667D01*
X1583589Y-474000D01*
X1583716Y-473334D01*
X1583969Y-472750D01*
X1584349Y-472417D01*
X1584729Y-472334D01*
X1585109Y-472417D01*
X1585489Y-472750D01*
X1585742Y-473334D01*
X1585806Y-474000D01*
X1585742Y-474667D01*
X1585489Y-475250D01*
X1585109Y-475584D01*
X1584729Y-475667D01*
G01X1588942D02*
Y-472334D01*
G01Y-473000D02*
X1589259Y-472667D01*
X1589576Y-472417D01*
X1590019Y-472334D01*
X1590336Y-472417D01*
X1590716Y-472667D01*
G01X1598762Y-475667D02*
Y-470667D01*
X1600282D01*
X1600789Y-470917D01*
X1601169Y-471500D01*
X1601296Y-472167D01*
X1601169Y-472834D01*
X1600852Y-473334D01*
X1600282Y-473584D01*
X1598762D01*
G01X1606269Y-475667D02*
Y-472334D01*
G01Y-472917D02*
X1606016Y-472584D01*
X1605636Y-472417D01*
X1605192Y-472334D01*
X1604749Y-472500D01*
X1604369Y-472834D01*
X1604116Y-473334D01*
X1603989Y-474000D01*
X1604116Y-474667D01*
X1604369Y-475167D01*
X1604749Y-475500D01*
X1605192Y-475667D01*
X1605636Y-475584D01*
X1606016Y-475334D01*
X1606269Y-475000D01*
G01X1609152Y-475667D02*
Y-472334D01*
G01Y-473167D02*
X1609406Y-472750D01*
X1609786Y-472417D01*
X1610292Y-472334D01*
X1610736Y-472417D01*
X1611116Y-472750D01*
X1611306Y-473334D01*
Y-475667D01*
G01X1614379Y-473417D02*
X1616406D01*
X1616216Y-472834D01*
X1615899Y-472500D01*
X1615456Y-472334D01*
X1615012Y-472417D01*
X1614632Y-472667D01*
X1614379Y-473250D01*
X1614252Y-473750D01*
Y-474250D01*
X1614379Y-474750D01*
X1614696Y-475250D01*
X1615076Y-475584D01*
X1615519Y-475667D01*
X1615962Y-475500D01*
X1616406Y-475000D01*
G01X1620429Y-475667D02*
Y-470667D01*
G01X1631136Y-473000D02*
X1631389Y-472750D01*
X1631579Y-472334D01*
X1631706Y-471750D01*
X1631579Y-471250D01*
X1631326Y-470917D01*
X1630882Y-470667D01*
X1629172D01*
Y-475667D01*
X1631262D01*
X1631706Y-475334D01*
X1631959Y-474834D01*
X1632086Y-474250D01*
X1631959Y-473667D01*
X1631579Y-473167D01*
X1631136Y-473000D01*
X1629172D01*
G01X1635729Y-475667D02*
X1635349Y-475584D01*
X1634969Y-475250D01*
X1634716Y-474667D01*
X1634589Y-474000D01*
X1634716Y-473334D01*
X1634969Y-472750D01*
X1635349Y-472417D01*
X1635729Y-472334D01*
X1636109Y-472417D01*
X1636489Y-472750D01*
X1636742Y-473334D01*
X1636806Y-474000D01*
X1636742Y-474667D01*
X1636489Y-475250D01*
X1636109Y-475584D01*
X1635729Y-475667D01*
G01X1641969D02*
Y-472334D01*
G01Y-472917D02*
X1641716Y-472584D01*
X1641336Y-472417D01*
X1640892Y-472334D01*
X1640449Y-472500D01*
X1640069Y-472834D01*
X1639816Y-473334D01*
X1639689Y-474000D01*
X1639816Y-474667D01*
X1640069Y-475167D01*
X1640449Y-475500D01*
X1640892Y-475667D01*
X1641336Y-475584D01*
X1641716Y-475334D01*
X1641969Y-475000D01*
G01X1645042Y-475667D02*
Y-472334D01*
G01Y-473000D02*
X1645359Y-472667D01*
X1645676Y-472417D01*
X1646119Y-472334D01*
X1646436Y-472417D01*
X1646816Y-472667D01*
G01X1652169Y-470667D02*
Y-475667D01*
G01Y-474917D02*
X1651916Y-475334D01*
X1651536Y-475584D01*
X1651092Y-475667D01*
X1650586Y-475500D01*
X1650206Y-475084D01*
X1649952Y-474584D01*
X1649889Y-474000D01*
X1649952Y-473417D01*
X1650206Y-472917D01*
X1650586Y-472500D01*
X1651092Y-472334D01*
X1651536Y-472417D01*
X1651852Y-472584D01*
X1652169Y-472917D01*
G01X1501926Y-437867D02*
Y-432867D01*
X1504332D01*
G01X1503446Y-435284D02*
X1501926D01*
G01X1508229Y-434534D02*
Y-437867D01*
G01Y-433200D02*
X1508102Y-433117D01*
Y-432950D01*
X1508229Y-432867D01*
X1508356Y-432950D01*
Y-433117D01*
X1508229Y-433200D01*
G01X1514469Y-432867D02*
Y-437867D01*
G01Y-437117D02*
X1514216Y-437534D01*
X1513836Y-437784D01*
X1513392Y-437867D01*
X1512886Y-437700D01*
X1512506Y-437284D01*
X1512252Y-436784D01*
X1512189Y-436200D01*
X1512252Y-435617D01*
X1512506Y-435117D01*
X1512886Y-434700D01*
X1513392Y-434534D01*
X1513836Y-434617D01*
X1514152Y-434784D01*
X1514469Y-435117D01*
G01X1517352Y-434534D02*
Y-436867D01*
X1517606Y-437450D01*
X1517986Y-437784D01*
X1518429Y-437867D01*
X1518872Y-437784D01*
X1519252Y-437450D01*
X1519506Y-436867D01*
G01Y-437867D02*
Y-434534D01*
G01X1524542Y-434950D02*
X1524099Y-434617D01*
X1523719Y-434534D01*
X1523212Y-434700D01*
X1522832Y-435034D01*
X1522579Y-435617D01*
X1522516Y-436200D01*
X1522579Y-436784D01*
X1522832Y-437284D01*
X1523212Y-437700D01*
X1523719Y-437867D01*
X1524162Y-437700D01*
X1524542Y-437367D01*
G01X1528629Y-434534D02*
Y-437867D01*
G01Y-433200D02*
X1528502Y-433117D01*
Y-432950D01*
X1528629Y-432867D01*
X1528756Y-432950D01*
Y-433117D01*
X1528629Y-433200D01*
G01X1534869Y-437867D02*
Y-434534D01*
G01Y-435117D02*
X1534616Y-434784D01*
X1534236Y-434617D01*
X1533792Y-434534D01*
X1533349Y-434700D01*
X1532969Y-435034D01*
X1532716Y-435534D01*
X1532589Y-436200D01*
X1532716Y-436867D01*
X1532969Y-437367D01*
X1533349Y-437700D01*
X1533792Y-437867D01*
X1534236Y-437784D01*
X1534616Y-437534D01*
X1534869Y-437200D01*
G01X1538829Y-437867D02*
Y-432867D01*
G01X1547382Y-437867D02*
Y-432867D01*
X1549029Y-437034D01*
X1550676Y-432867D01*
Y-437867D01*
G01X1555269D02*
Y-434534D01*
G01Y-435117D02*
X1555016Y-434784D01*
X1554636Y-434617D01*
X1554192Y-434534D01*
X1553749Y-434700D01*
X1553369Y-435034D01*
X1553116Y-435534D01*
X1552989Y-436200D01*
X1553116Y-436867D01*
X1553369Y-437367D01*
X1553749Y-437700D01*
X1554192Y-437867D01*
X1554636Y-437784D01*
X1555016Y-437534D01*
X1555269Y-437200D01*
G01X1558342Y-437867D02*
Y-434534D01*
G01Y-435200D02*
X1558659Y-434867D01*
X1558976Y-434617D01*
X1559419Y-434534D01*
X1559736Y-434617D01*
X1560116Y-434867D01*
G01X1563252Y-437867D02*
Y-432867D01*
G01X1565279Y-434534D02*
X1563252Y-436450D01*
G01X1564076Y-435700D02*
X1565406Y-437867D01*
G01X1569429Y-438034D02*
X1569302Y-437950D01*
Y-437784D01*
X1569429Y-437700D01*
X1569556Y-437784D01*
Y-437950D01*
X1569429Y-438034D01*
G01Y-435784D02*
X1569302Y-435700D01*
Y-435534D01*
X1569429Y-435450D01*
X1569556Y-435534D01*
Y-435700D01*
X1569429Y-435784D01*
G01X1578236Y-437867D02*
Y-432867D01*
X1579502D01*
X1580009Y-433117D01*
X1580389Y-433450D01*
X1580706Y-433950D01*
X1580959Y-434534D01*
X1581022Y-435367D01*
X1580959Y-436200D01*
X1580706Y-436784D01*
X1580389Y-437284D01*
X1580009Y-437617D01*
X1579502Y-437867D01*
X1578236D01*
G01X1584729Y-434534D02*
Y-437867D01*
G01Y-433200D02*
X1584602Y-433117D01*
Y-432950D01*
X1584729Y-432867D01*
X1584856Y-432950D01*
Y-433117D01*
X1584729Y-433200D01*
G01X1590969Y-437867D02*
Y-434534D01*
G01Y-435117D02*
X1590716Y-434784D01*
X1590336Y-434617D01*
X1589892Y-434534D01*
X1589449Y-434700D01*
X1589069Y-435034D01*
X1588816Y-435534D01*
X1588689Y-436200D01*
X1588816Y-436867D01*
X1589069Y-437367D01*
X1589449Y-437700D01*
X1589892Y-437867D01*
X1590336Y-437784D01*
X1590716Y-437534D01*
X1590969Y-437200D01*
G01X1593029Y-437867D02*
Y-434534D01*
G01Y-435450D02*
X1593219Y-435034D01*
X1593536Y-434700D01*
X1593979Y-434534D01*
X1594422Y-434700D01*
X1594739Y-435034D01*
X1594929Y-435450D01*
Y-437867D01*
G01Y-435450D02*
X1595119Y-435034D01*
X1595436Y-434700D01*
X1595879Y-434534D01*
X1596322Y-434700D01*
X1596639Y-435034D01*
X1596829Y-435534D01*
Y-437867D01*
G01X1599079Y-435617D02*
X1601106D01*
X1600916Y-435034D01*
X1600599Y-434700D01*
X1600156Y-434534D01*
X1599712Y-434617D01*
X1599332Y-434867D01*
X1599079Y-435450D01*
X1598952Y-435950D01*
Y-436450D01*
X1599079Y-436950D01*
X1599396Y-437450D01*
X1599776Y-437784D01*
X1600219Y-437867D01*
X1600662Y-437700D01*
X1601106Y-437200D01*
G01X1605129Y-432867D02*
Y-437867D01*
G01X1604242Y-434534D02*
X1606016D01*
G01X1609279Y-435617D02*
X1611306D01*
X1611116Y-435034D01*
X1610799Y-434700D01*
X1610356Y-434534D01*
X1609912Y-434617D01*
X1609532Y-434867D01*
X1609279Y-435450D01*
X1609152Y-435950D01*
Y-436450D01*
X1609279Y-436950D01*
X1609596Y-437450D01*
X1609976Y-437784D01*
X1610419Y-437867D01*
X1610862Y-437700D01*
X1611306Y-437200D01*
G01X1614442Y-437867D02*
Y-434534D01*
G01Y-435200D02*
X1614759Y-434867D01*
X1615076Y-434617D01*
X1615519Y-434534D01*
X1615836Y-434617D01*
X1616216Y-434867D01*
G01X1625529Y-437867D02*
Y-432867D01*
X1624769Y-433867D01*
G01Y-437867D02*
X1626289D01*
G01X1628729D02*
Y-434534D01*
G01Y-435450D02*
X1628919Y-435034D01*
X1629236Y-434700D01*
X1629679Y-434534D01*
X1630122Y-434700D01*
X1630439Y-435034D01*
X1630629Y-435450D01*
Y-437867D01*
G01Y-435450D02*
X1630819Y-435034D01*
X1631136Y-434700D01*
X1631579Y-434534D01*
X1632022Y-434700D01*
X1632339Y-435034D01*
X1632529Y-435534D01*
Y-437867D01*
G01X1633829D02*
Y-434534D01*
G01Y-435450D02*
X1634019Y-435034D01*
X1634336Y-434700D01*
X1634779Y-434534D01*
X1635222Y-434700D01*
X1635539Y-435034D01*
X1635729Y-435450D01*
Y-437867D01*
G01Y-435450D02*
X1635919Y-435034D01*
X1636236Y-434700D01*
X1636679Y-434534D01*
X1637122Y-434700D01*
X1637439Y-435034D01*
X1637629Y-435534D01*
Y-437867D01*
G01X1647322Y-433284D02*
X1646942Y-433034D01*
X1646499Y-432867D01*
X1645992D01*
X1645422Y-433117D01*
X1644979Y-433534D01*
X1644662Y-434034D01*
X1644409Y-434867D01*
X1644346Y-435617D01*
X1644472Y-436367D01*
X1644662Y-436867D01*
X1645042Y-437367D01*
X1645486Y-437700D01*
X1645929Y-437867D01*
X1646372D01*
X1646816Y-437700D01*
X1647196Y-437450D01*
X1647512Y-437117D01*
G01X1651029Y-437867D02*
X1650649Y-437784D01*
X1650269Y-437450D01*
X1650016Y-436867D01*
X1649889Y-436200D01*
X1650016Y-435534D01*
X1650269Y-434950D01*
X1650649Y-434617D01*
X1651029Y-434534D01*
X1651409Y-434617D01*
X1651789Y-434950D01*
X1652042Y-435534D01*
X1652106Y-436200D01*
X1652042Y-436867D01*
X1651789Y-437450D01*
X1651409Y-437784D01*
X1651029Y-437867D01*
G01X1654989Y-439534D02*
Y-434534D01*
G01Y-435284D02*
X1655306Y-434867D01*
X1655622Y-434617D01*
X1656129Y-434534D01*
X1656572Y-434617D01*
X1657016Y-435034D01*
X1657206Y-435617D01*
X1657269Y-436200D01*
X1657206Y-436784D01*
X1657016Y-437367D01*
X1656636Y-437700D01*
X1656129Y-437867D01*
X1655686Y-437784D01*
X1655242Y-437534D01*
X1654989Y-437200D01*
G01X1660089Y-439534D02*
Y-434534D01*
G01Y-435284D02*
X1660406Y-434867D01*
X1660722Y-434617D01*
X1661229Y-434534D01*
X1661672Y-434617D01*
X1662116Y-435034D01*
X1662306Y-435617D01*
X1662369Y-436200D01*
X1662306Y-436784D01*
X1662116Y-437367D01*
X1661736Y-437700D01*
X1661229Y-437867D01*
X1660786Y-437784D01*
X1660342Y-437534D01*
X1660089Y-437200D01*
G01X1665379Y-435617D02*
X1667406D01*
X1667216Y-435034D01*
X1666899Y-434700D01*
X1666456Y-434534D01*
X1666012Y-434617D01*
X1665632Y-434867D01*
X1665379Y-435450D01*
X1665252Y-435950D01*
Y-436450D01*
X1665379Y-436950D01*
X1665696Y-437450D01*
X1666076Y-437784D01*
X1666519Y-437867D01*
X1666962Y-437700D01*
X1667406Y-437200D01*
G01X1670542Y-437867D02*
Y-434534D01*
G01Y-435200D02*
X1670859Y-434867D01*
X1671176Y-434617D01*
X1671619Y-434534D01*
X1671936Y-434617D01*
X1672316Y-434867D01*
G01X1578236Y-450467D02*
Y-445467D01*
X1579502D01*
X1580009Y-445717D01*
X1580389Y-446050D01*
X1580706Y-446550D01*
X1580959Y-447134D01*
X1581022Y-447967D01*
X1580959Y-448800D01*
X1580706Y-449384D01*
X1580389Y-449884D01*
X1580009Y-450217D01*
X1579502Y-450467D01*
X1578236D01*
G01X1584729Y-447134D02*
Y-450467D01*
G01Y-445800D02*
X1584602Y-445717D01*
Y-445550D01*
X1584729Y-445467D01*
X1584856Y-445550D01*
Y-445717D01*
X1584729Y-445800D01*
G01X1590969Y-450467D02*
Y-447134D01*
G01Y-447717D02*
X1590716Y-447384D01*
X1590336Y-447217D01*
X1589892Y-447134D01*
X1589449Y-447300D01*
X1589069Y-447634D01*
X1588816Y-448134D01*
X1588689Y-448800D01*
X1588816Y-449467D01*
X1589069Y-449967D01*
X1589449Y-450300D01*
X1589892Y-450467D01*
X1590336Y-450384D01*
X1590716Y-450134D01*
X1590969Y-449800D01*
G01X1593029Y-450467D02*
Y-447134D01*
G01Y-448050D02*
X1593219Y-447634D01*
X1593536Y-447300D01*
X1593979Y-447134D01*
X1594422Y-447300D01*
X1594739Y-447634D01*
X1594929Y-448050D01*
Y-450467D01*
G01Y-448050D02*
X1595119Y-447634D01*
X1595436Y-447300D01*
X1595879Y-447134D01*
X1596322Y-447300D01*
X1596639Y-447634D01*
X1596829Y-448134D01*
Y-450467D01*
G01X1599079Y-448217D02*
X1601106D01*
X1600916Y-447634D01*
X1600599Y-447300D01*
X1600156Y-447134D01*
X1599712Y-447217D01*
X1599332Y-447467D01*
X1599079Y-448050D01*
X1598952Y-448550D01*
Y-449050D01*
X1599079Y-449550D01*
X1599396Y-450050D01*
X1599776Y-450384D01*
X1600219Y-450467D01*
X1600662Y-450300D01*
X1601106Y-449800D01*
G01X1605129Y-445467D02*
Y-450467D01*
G01X1604242Y-447134D02*
X1606016D01*
G01X1609279Y-448217D02*
X1611306D01*
X1611116Y-447634D01*
X1610799Y-447300D01*
X1610356Y-447134D01*
X1609912Y-447217D01*
X1609532Y-447467D01*
X1609279Y-448050D01*
X1609152Y-448550D01*
Y-449050D01*
X1609279Y-449550D01*
X1609596Y-450050D01*
X1609976Y-450384D01*
X1610419Y-450467D01*
X1610862Y-450300D01*
X1611306Y-449800D01*
G01X1614442Y-450467D02*
Y-447134D01*
G01Y-447800D02*
X1614759Y-447467D01*
X1615076Y-447217D01*
X1615519Y-447134D01*
X1615836Y-447217D01*
X1616216Y-447467D01*
G01X1624136Y-449467D02*
X1624516Y-450050D01*
X1625022Y-450384D01*
X1625592Y-450467D01*
X1626099Y-450384D01*
X1626606Y-449967D01*
X1626922Y-449467D01*
X1626986Y-448967D01*
X1626859Y-448384D01*
X1626416Y-447967D01*
X1625972Y-447800D01*
X1625402D01*
G01X1625972D02*
X1626352Y-447550D01*
X1626669Y-447134D01*
X1626796Y-446634D01*
X1626669Y-446134D01*
X1626352Y-445717D01*
X1625782Y-445467D01*
X1625212Y-445550D01*
X1624642Y-445884D01*
G01X1628729Y-450467D02*
Y-447134D01*
G01Y-448050D02*
X1628919Y-447634D01*
X1629236Y-447300D01*
X1629679Y-447134D01*
X1630122Y-447300D01*
X1630439Y-447634D01*
X1630629Y-448050D01*
Y-450467D01*
G01Y-448050D02*
X1630819Y-447634D01*
X1631136Y-447300D01*
X1631579Y-447134D01*
X1632022Y-447300D01*
X1632339Y-447634D01*
X1632529Y-448134D01*
Y-450467D01*
G01X1633829D02*
Y-447134D01*
G01Y-448050D02*
X1634019Y-447634D01*
X1634336Y-447300D01*
X1634779Y-447134D01*
X1635222Y-447300D01*
X1635539Y-447634D01*
X1635729Y-448050D01*
Y-450467D01*
G01Y-448050D02*
X1635919Y-447634D01*
X1636236Y-447300D01*
X1636679Y-447134D01*
X1637122Y-447300D01*
X1637439Y-447634D01*
X1637629Y-448134D01*
Y-450467D01*
G01X1644599Y-449800D02*
X1645106Y-450217D01*
X1645676Y-450467D01*
X1646182D01*
X1646689Y-450217D01*
X1647069Y-449800D01*
X1647259Y-449217D01*
X1647132Y-448634D01*
X1646816Y-448134D01*
X1646246Y-447800D01*
X1645486Y-447634D01*
X1645042Y-447300D01*
X1644852Y-446717D01*
X1644979Y-446134D01*
X1645296Y-445717D01*
X1645739Y-445467D01*
X1646182D01*
X1646626Y-445634D01*
X1647006Y-446050D01*
G01X1651029Y-450467D02*
X1650649Y-450384D01*
X1650269Y-450050D01*
X1650016Y-449467D01*
X1649889Y-448800D01*
X1650016Y-448134D01*
X1650269Y-447550D01*
X1650649Y-447217D01*
X1651029Y-447134D01*
X1651409Y-447217D01*
X1651789Y-447550D01*
X1652042Y-448134D01*
X1652106Y-448800D01*
X1652042Y-449467D01*
X1651789Y-450050D01*
X1651409Y-450384D01*
X1651029Y-450467D01*
G01X1656129D02*
Y-445467D01*
G01X1662369D02*
Y-450467D01*
G01Y-449717D02*
X1662116Y-450134D01*
X1661736Y-450384D01*
X1661292Y-450467D01*
X1660786Y-450300D01*
X1660406Y-449884D01*
X1660152Y-449384D01*
X1660089Y-448800D01*
X1660152Y-448217D01*
X1660406Y-447717D01*
X1660786Y-447300D01*
X1661292Y-447134D01*
X1661736Y-447217D01*
X1662052Y-447384D01*
X1662369Y-447717D01*
G01X1665379Y-448217D02*
X1667406D01*
X1667216Y-447634D01*
X1666899Y-447300D01*
X1666456Y-447134D01*
X1666012Y-447217D01*
X1665632Y-447467D01*
X1665379Y-448050D01*
X1665252Y-448550D01*
Y-449050D01*
X1665379Y-449550D01*
X1665696Y-450050D01*
X1666076Y-450384D01*
X1666519Y-450467D01*
X1666962Y-450300D01*
X1667406Y-449800D01*
G01X1670542Y-450467D02*
Y-447134D01*
G01Y-447800D02*
X1670859Y-447467D01*
X1671176Y-447217D01*
X1671619Y-447134D01*
X1671936Y-447217D01*
X1672316Y-447467D01*
G01X1674629Y-450467D02*
Y-447134D01*
G01Y-448050D02*
X1674819Y-447634D01*
X1675136Y-447300D01*
X1675579Y-447134D01*
X1676022Y-447300D01*
X1676339Y-447634D01*
X1676529Y-448050D01*
Y-450467D01*
G01Y-448050D02*
X1676719Y-447634D01*
X1677036Y-447300D01*
X1677479Y-447134D01*
X1677922Y-447300D01*
X1678239Y-447634D01*
X1678429Y-448134D01*
Y-450467D01*
G01X1682769D02*
Y-447134D01*
G01Y-447717D02*
X1682516Y-447384D01*
X1682136Y-447217D01*
X1681692Y-447134D01*
X1681249Y-447300D01*
X1680869Y-447634D01*
X1680616Y-448134D01*
X1680489Y-448800D01*
X1680616Y-449467D01*
X1680869Y-449967D01*
X1681249Y-450300D01*
X1681692Y-450467D01*
X1682136Y-450384D01*
X1682516Y-450134D01*
X1682769Y-449800D01*
G01X1685779Y-449884D02*
X1686096Y-450217D01*
X1686539Y-450467D01*
X1686919D01*
X1687299Y-450300D01*
X1687552Y-450050D01*
X1687679Y-449717D01*
X1687616Y-449217D01*
X1687362Y-448967D01*
X1686222Y-448467D01*
X1685969Y-447884D01*
X1686096Y-447467D01*
X1686349Y-447217D01*
X1686729Y-447134D01*
X1687109Y-447217D01*
X1687489Y-447467D01*
G01X1690752Y-450467D02*
Y-445467D01*
G01X1692779Y-447134D02*
X1690752Y-449050D01*
G01X1691576Y-448300D02*
X1692906Y-450467D01*
G01X1575317Y-376175D02*
Y-381175D01*
G01X1573860Y-376175D02*
X1576774D01*
G01X1580417Y-381175D02*
X1580037Y-381092D01*
X1579657Y-380758D01*
X1579404Y-380175D01*
X1579277Y-379508D01*
X1579404Y-378842D01*
X1579657Y-378258D01*
X1580037Y-377925D01*
X1580417Y-377842D01*
X1580797Y-377925D01*
X1581177Y-378258D01*
X1581430Y-378842D01*
X1581494Y-379508D01*
X1581430Y-380175D01*
X1581177Y-380758D01*
X1580797Y-381092D01*
X1580417Y-381175D01*
G01X1585517D02*
Y-376175D01*
G01X1589667Y-378925D02*
X1591694D01*
X1591504Y-378342D01*
X1591187Y-378008D01*
X1590744Y-377842D01*
X1590300Y-377925D01*
X1589920Y-378175D01*
X1589667Y-378758D01*
X1589540Y-379258D01*
Y-379758D01*
X1589667Y-380258D01*
X1589984Y-380758D01*
X1590364Y-381092D01*
X1590807Y-381175D01*
X1591250Y-381008D01*
X1591694Y-380508D01*
G01X1594830Y-381175D02*
Y-377842D01*
G01Y-378508D02*
X1595147Y-378175D01*
X1595464Y-377925D01*
X1595907Y-377842D01*
X1596224Y-377925D01*
X1596604Y-378175D01*
G01X1601957Y-381175D02*
Y-377842D01*
G01Y-378425D02*
X1601704Y-378092D01*
X1601324Y-377925D01*
X1600880Y-377842D01*
X1600437Y-378008D01*
X1600057Y-378342D01*
X1599804Y-378842D01*
X1599677Y-379508D01*
X1599804Y-380175D01*
X1600057Y-380675D01*
X1600437Y-381008D01*
X1600880Y-381175D01*
X1601324Y-381092D01*
X1601704Y-380842D01*
X1601957Y-380508D01*
G01X1604840Y-381175D02*
Y-377842D01*
G01Y-378675D02*
X1605094Y-378258D01*
X1605474Y-377925D01*
X1605980Y-377842D01*
X1606424Y-377925D01*
X1606804Y-378258D01*
X1606994Y-378842D01*
Y-381175D01*
G01X1612030Y-378258D02*
X1611587Y-377925D01*
X1611207Y-377842D01*
X1610700Y-378008D01*
X1610320Y-378342D01*
X1610067Y-378925D01*
X1610004Y-379508D01*
X1610067Y-380092D01*
X1610320Y-380592D01*
X1610700Y-381008D01*
X1611207Y-381175D01*
X1611650Y-381008D01*
X1612030Y-380675D01*
G01X1615167Y-378925D02*
X1617194D01*
X1617004Y-378342D01*
X1616687Y-378008D01*
X1616244Y-377842D01*
X1615800Y-377925D01*
X1615420Y-378175D01*
X1615167Y-378758D01*
X1615040Y-379258D01*
Y-379758D01*
X1615167Y-380258D01*
X1615484Y-380758D01*
X1615864Y-381092D01*
X1616307Y-381175D01*
X1616750Y-381008D01*
X1617194Y-380508D01*
G01X1625620Y-379508D02*
X1627140D01*
G01X1626317Y-378425D02*
Y-380592D01*
G01X1631417Y-376175D02*
X1630910Y-376342D01*
X1630530Y-376758D01*
X1630277Y-377258D01*
X1630087Y-377925D01*
X1630024Y-378675D01*
X1630087Y-379425D01*
X1630277Y-380092D01*
X1630530Y-380592D01*
X1630910Y-381008D01*
X1631417Y-381175D01*
X1631924Y-381008D01*
X1632304Y-380592D01*
X1632557Y-380092D01*
X1632747Y-379425D01*
X1632810Y-378675D01*
X1632747Y-377925D01*
X1632557Y-377258D01*
X1632304Y-376758D01*
X1631924Y-376342D01*
X1631417Y-376175D01*
G01X1636517Y-381342D02*
X1636390Y-381258D01*
Y-381092D01*
X1636517Y-381008D01*
X1636644Y-381092D01*
Y-381258D01*
X1636517Y-381342D01*
G01X1641617Y-376175D02*
X1641110Y-376342D01*
X1640730Y-376758D01*
X1640477Y-377258D01*
X1640287Y-377925D01*
X1640224Y-378675D01*
X1640287Y-379425D01*
X1640477Y-380092D01*
X1640730Y-380592D01*
X1641110Y-381008D01*
X1641617Y-381175D01*
X1642124Y-381008D01*
X1642504Y-380592D01*
X1642757Y-380092D01*
X1642947Y-379425D01*
X1643010Y-378675D01*
X1642947Y-377925D01*
X1642757Y-377258D01*
X1642504Y-376758D01*
X1642124Y-376342D01*
X1641617Y-376175D01*
G01X1645324Y-380425D02*
X1645704Y-380842D01*
X1646147Y-381092D01*
X1646717Y-381175D01*
X1647287Y-381008D01*
X1647730Y-380675D01*
X1648047Y-380092D01*
X1648110Y-379425D01*
X1647984Y-378758D01*
X1647667Y-378342D01*
X1647224Y-378008D01*
X1646780Y-377925D01*
X1646337Y-378008D01*
X1645767Y-378342D01*
X1645957Y-376175D01*
X1647667D01*
G01X1651817D02*
X1651310Y-376342D01*
X1650930Y-376758D01*
X1650677Y-377258D01*
X1650487Y-377925D01*
X1650424Y-378675D01*
X1650487Y-379425D01*
X1650677Y-380092D01*
X1650930Y-380592D01*
X1651310Y-381008D01*
X1651817Y-381175D01*
X1652324Y-381008D01*
X1652704Y-380592D01*
X1652957Y-380092D01*
X1653147Y-379425D01*
X1653210Y-378675D01*
X1653147Y-377925D01*
X1652957Y-377258D01*
X1652704Y-376758D01*
X1652324Y-376342D01*
X1651817Y-376175D01*
G01X1656917Y-381175D02*
X1657360Y-381092D01*
X1657867Y-380842D01*
X1658184Y-380425D01*
X1658310Y-379842D01*
X1658184Y-379258D01*
X1657804Y-378758D01*
X1657234Y-378508D01*
X1656600D01*
X1656220Y-378342D01*
X1655904Y-377925D01*
X1655777Y-377342D01*
X1655967Y-376758D01*
X1656410Y-376342D01*
X1656917Y-376175D01*
X1657424Y-376342D01*
X1657867Y-376758D01*
X1658057Y-377342D01*
X1657930Y-377925D01*
X1657614Y-378342D01*
X1657234Y-378508D01*
X1656600D01*
X1656030Y-378758D01*
X1655650Y-379258D01*
X1655524Y-379842D01*
X1655650Y-380425D01*
X1655967Y-380842D01*
X1656474Y-381092D01*
X1656917Y-381175D01*
G01X1660117D02*
Y-377842D01*
G01Y-378758D02*
X1660307Y-378342D01*
X1660624Y-378008D01*
X1661067Y-377842D01*
X1661510Y-378008D01*
X1661827Y-378342D01*
X1662017Y-378758D01*
Y-381175D01*
G01Y-378758D02*
X1662207Y-378342D01*
X1662524Y-378008D01*
X1662967Y-377842D01*
X1663410Y-378008D01*
X1663727Y-378342D01*
X1663917Y-378842D01*
Y-381175D01*
G01X1665217D02*
Y-377842D01*
G01Y-378758D02*
X1665407Y-378342D01*
X1665724Y-378008D01*
X1666167Y-377842D01*
X1666610Y-378008D01*
X1666927Y-378342D01*
X1667117Y-378758D01*
Y-381175D01*
G01Y-378758D02*
X1667307Y-378342D01*
X1667624Y-378008D01*
X1668067Y-377842D01*
X1668510Y-378008D01*
X1668827Y-378342D01*
X1669017Y-378842D01*
Y-381175D01*
G01X1671077Y-381342D02*
X1673357Y-376175D01*
G01X1676494Y-379508D02*
X1678140D01*
G01X1682417Y-376175D02*
X1681910Y-376342D01*
X1681530Y-376758D01*
X1681277Y-377258D01*
X1681087Y-377925D01*
X1681024Y-378675D01*
X1681087Y-379425D01*
X1681277Y-380092D01*
X1681530Y-380592D01*
X1681910Y-381008D01*
X1682417Y-381175D01*
X1682924Y-381008D01*
X1683304Y-380592D01*
X1683557Y-380092D01*
X1683747Y-379425D01*
X1683810Y-378675D01*
X1683747Y-377925D01*
X1683557Y-377258D01*
X1683304Y-376758D01*
X1682924Y-376342D01*
X1682417Y-376175D01*
G01X1687517Y-381342D02*
X1687390Y-381258D01*
Y-381092D01*
X1687517Y-381008D01*
X1687644Y-381092D01*
Y-381258D01*
X1687517Y-381342D01*
G01X1692617Y-376175D02*
X1692110Y-376342D01*
X1691730Y-376758D01*
X1691477Y-377258D01*
X1691287Y-377925D01*
X1691224Y-378675D01*
X1691287Y-379425D01*
X1691477Y-380092D01*
X1691730Y-380592D01*
X1692110Y-381008D01*
X1692617Y-381175D01*
X1693124Y-381008D01*
X1693504Y-380592D01*
X1693757Y-380092D01*
X1693947Y-379425D01*
X1694010Y-378675D01*
X1693947Y-377925D01*
X1693757Y-377258D01*
X1693504Y-376758D01*
X1693124Y-376342D01*
X1692617Y-376175D01*
G01X1697717D02*
X1697210Y-376342D01*
X1696830Y-376758D01*
X1696577Y-377258D01*
X1696387Y-377925D01*
X1696324Y-378675D01*
X1696387Y-379425D01*
X1696577Y-380092D01*
X1696830Y-380592D01*
X1697210Y-381008D01*
X1697717Y-381175D01*
X1698224Y-381008D01*
X1698604Y-380592D01*
X1698857Y-380092D01*
X1699047Y-379425D01*
X1699110Y-378675D01*
X1699047Y-377925D01*
X1698857Y-377258D01*
X1698604Y-376758D01*
X1698224Y-376342D01*
X1697717Y-376175D01*
G01X1702817D02*
X1702310Y-376342D01*
X1701930Y-376758D01*
X1701677Y-377258D01*
X1701487Y-377925D01*
X1701424Y-378675D01*
X1701487Y-379425D01*
X1701677Y-380092D01*
X1701930Y-380592D01*
X1702310Y-381008D01*
X1702817Y-381175D01*
X1703324Y-381008D01*
X1703704Y-380592D01*
X1703957Y-380092D01*
X1704147Y-379425D01*
X1704210Y-378675D01*
X1704147Y-377925D01*
X1703957Y-377258D01*
X1703704Y-376758D01*
X1703324Y-376342D01*
X1702817Y-376175D01*
G01X1707917D02*
X1707410Y-376342D01*
X1707030Y-376758D01*
X1706777Y-377258D01*
X1706587Y-377925D01*
X1706524Y-378675D01*
X1706587Y-379425D01*
X1706777Y-380092D01*
X1707030Y-380592D01*
X1707410Y-381008D01*
X1707917Y-381175D01*
X1708424Y-381008D01*
X1708804Y-380592D01*
X1709057Y-380092D01*
X1709247Y-379425D01*
X1709310Y-378675D01*
X1709247Y-377925D01*
X1709057Y-377258D01*
X1708804Y-376758D01*
X1708424Y-376342D01*
X1707917Y-376175D01*
G01X1711117Y-381175D02*
Y-377842D01*
G01Y-378758D02*
X1711307Y-378342D01*
X1711624Y-378008D01*
X1712067Y-377842D01*
X1712510Y-378008D01*
X1712827Y-378342D01*
X1713017Y-378758D01*
Y-381175D01*
G01Y-378758D02*
X1713207Y-378342D01*
X1713524Y-378008D01*
X1713967Y-377842D01*
X1714410Y-378008D01*
X1714727Y-378342D01*
X1714917Y-378842D01*
Y-381175D01*
G01X1716217D02*
Y-377842D01*
G01Y-378758D02*
X1716407Y-378342D01*
X1716724Y-378008D01*
X1717167Y-377842D01*
X1717610Y-378008D01*
X1717927Y-378342D01*
X1718117Y-378758D01*
Y-381175D01*
G01Y-378758D02*
X1718307Y-378342D01*
X1718624Y-378008D01*
X1719067Y-377842D01*
X1719510Y-378008D01*
X1719827Y-378342D01*
X1720017Y-378842D01*
Y-381175D01*
G01X1503917Y-363575D02*
Y-368575D01*
G01X1502460Y-363575D02*
X1505374D01*
G01X1509017Y-368575D02*
X1508637Y-368492D01*
X1508257Y-368158D01*
X1508004Y-367575D01*
X1507877Y-366908D01*
X1508004Y-366242D01*
X1508257Y-365658D01*
X1508637Y-365325D01*
X1509017Y-365242D01*
X1509397Y-365325D01*
X1509777Y-365658D01*
X1510030Y-366242D01*
X1510094Y-366908D01*
X1510030Y-367575D01*
X1509777Y-368158D01*
X1509397Y-368492D01*
X1509017Y-368575D01*
G01X1514117D02*
X1513737Y-368492D01*
X1513357Y-368158D01*
X1513104Y-367575D01*
X1512977Y-366908D01*
X1513104Y-366242D01*
X1513357Y-365658D01*
X1513737Y-365325D01*
X1514117Y-365242D01*
X1514497Y-365325D01*
X1514877Y-365658D01*
X1515130Y-366242D01*
X1515194Y-366908D01*
X1515130Y-367575D01*
X1514877Y-368158D01*
X1514497Y-368492D01*
X1514117Y-368575D01*
G01X1519217D02*
Y-363575D01*
G01X1524317Y-365242D02*
Y-368575D01*
G01Y-363908D02*
X1524190Y-363825D01*
Y-363658D01*
X1524317Y-363575D01*
X1524444Y-363658D01*
Y-363825D01*
X1524317Y-363908D01*
G01X1528340Y-368575D02*
Y-365242D01*
G01Y-366075D02*
X1528594Y-365658D01*
X1528974Y-365325D01*
X1529480Y-365242D01*
X1529924Y-365325D01*
X1530304Y-365658D01*
X1530494Y-366242D01*
Y-368575D01*
G01X1533630Y-369825D02*
X1534074Y-370158D01*
X1534580Y-370242D01*
X1535024Y-370158D01*
X1535404Y-369742D01*
X1535657Y-369158D01*
Y-365242D01*
G01Y-365908D02*
X1535404Y-365575D01*
X1535024Y-365325D01*
X1534580Y-365242D01*
X1534074Y-365408D01*
X1533757Y-365742D01*
X1533504Y-366325D01*
X1533377Y-366908D01*
X1533440Y-367408D01*
X1533694Y-367992D01*
X1534074Y-368408D01*
X1534580Y-368575D01*
X1534960Y-368492D01*
X1535404Y-368158D01*
X1535657Y-367825D01*
G01X1543387Y-368575D02*
Y-363575D01*
G01X1546047D02*
Y-368575D01*
G01Y-366075D02*
X1543387D01*
G01X1549817Y-368575D02*
X1549437Y-368492D01*
X1549057Y-368158D01*
X1548804Y-367575D01*
X1548677Y-366908D01*
X1548804Y-366242D01*
X1549057Y-365658D01*
X1549437Y-365325D01*
X1549817Y-365242D01*
X1550197Y-365325D01*
X1550577Y-365658D01*
X1550830Y-366242D01*
X1550894Y-366908D01*
X1550830Y-367575D01*
X1550577Y-368158D01*
X1550197Y-368492D01*
X1549817Y-368575D01*
G01X1554917D02*
Y-363575D01*
G01X1559067Y-366325D02*
X1561094D01*
X1560904Y-365742D01*
X1560587Y-365408D01*
X1560144Y-365242D01*
X1559700Y-365325D01*
X1559320Y-365575D01*
X1559067Y-366158D01*
X1558940Y-366658D01*
Y-367158D01*
X1559067Y-367658D01*
X1559384Y-368158D01*
X1559764Y-368492D01*
X1560207Y-368575D01*
X1560650Y-368408D01*
X1561094Y-367908D01*
G01X1565117Y-368742D02*
X1564990Y-368658D01*
Y-368492D01*
X1565117Y-368408D01*
X1565244Y-368492D01*
Y-368658D01*
X1565117Y-368742D01*
G01Y-366492D02*
X1564990Y-366408D01*
Y-366242D01*
X1565117Y-366158D01*
X1565244Y-366242D01*
Y-366408D01*
X1565117Y-366492D01*
G01X1573924Y-368575D02*
Y-363575D01*
X1575190D01*
X1575697Y-363825D01*
X1576077Y-364158D01*
X1576394Y-364658D01*
X1576647Y-365242D01*
X1576710Y-366075D01*
X1576647Y-366908D01*
X1576394Y-367492D01*
X1576077Y-367992D01*
X1575697Y-368325D01*
X1575190Y-368575D01*
X1573924D01*
G01X1580417Y-365242D02*
Y-368575D01*
G01Y-363908D02*
X1580290Y-363825D01*
Y-363658D01*
X1580417Y-363575D01*
X1580544Y-363658D01*
Y-363825D01*
X1580417Y-363908D01*
G01X1586657Y-368575D02*
Y-365242D01*
G01Y-365825D02*
X1586404Y-365492D01*
X1586024Y-365325D01*
X1585580Y-365242D01*
X1585137Y-365408D01*
X1584757Y-365742D01*
X1584504Y-366242D01*
X1584377Y-366908D01*
X1584504Y-367575D01*
X1584757Y-368075D01*
X1585137Y-368408D01*
X1585580Y-368575D01*
X1586024Y-368492D01*
X1586404Y-368242D01*
X1586657Y-367908D01*
G01X1588717Y-368575D02*
Y-365242D01*
G01Y-366158D02*
X1588907Y-365742D01*
X1589224Y-365408D01*
X1589667Y-365242D01*
X1590110Y-365408D01*
X1590427Y-365742D01*
X1590617Y-366158D01*
Y-368575D01*
G01Y-366158D02*
X1590807Y-365742D01*
X1591124Y-365408D01*
X1591567Y-365242D01*
X1592010Y-365408D01*
X1592327Y-365742D01*
X1592517Y-366242D01*
Y-368575D01*
G01X1594767Y-366325D02*
X1596794D01*
X1596604Y-365742D01*
X1596287Y-365408D01*
X1595844Y-365242D01*
X1595400Y-365325D01*
X1595020Y-365575D01*
X1594767Y-366158D01*
X1594640Y-366658D01*
Y-367158D01*
X1594767Y-367658D01*
X1595084Y-368158D01*
X1595464Y-368492D01*
X1595907Y-368575D01*
X1596350Y-368408D01*
X1596794Y-367908D01*
G01X1600817Y-363575D02*
Y-368575D01*
G01X1599930Y-365242D02*
X1601704D01*
G01X1604967Y-366325D02*
X1606994D01*
X1606804Y-365742D01*
X1606487Y-365408D01*
X1606044Y-365242D01*
X1605600Y-365325D01*
X1605220Y-365575D01*
X1604967Y-366158D01*
X1604840Y-366658D01*
Y-367158D01*
X1604967Y-367658D01*
X1605284Y-368158D01*
X1605664Y-368492D01*
X1606107Y-368575D01*
X1606550Y-368408D01*
X1606994Y-367908D01*
G01X1610130Y-368575D02*
Y-365242D01*
G01Y-365908D02*
X1610447Y-365575D01*
X1610764Y-365325D01*
X1611207Y-365242D01*
X1611524Y-365325D01*
X1611904Y-365575D01*
G01X1619824Y-367575D02*
X1620204Y-368158D01*
X1620710Y-368492D01*
X1621280Y-368575D01*
X1621787Y-368492D01*
X1622294Y-368075D01*
X1622610Y-367575D01*
X1622674Y-367075D01*
X1622547Y-366492D01*
X1622104Y-366075D01*
X1621660Y-365908D01*
X1621090D01*
G01X1621660D02*
X1622040Y-365658D01*
X1622357Y-365242D01*
X1622484Y-364742D01*
X1622357Y-364242D01*
X1622040Y-363825D01*
X1621470Y-363575D01*
X1620900Y-363658D01*
X1620330Y-363992D01*
G01X1626317Y-368742D02*
X1626190Y-368658D01*
Y-368492D01*
X1626317Y-368408D01*
X1626444Y-368492D01*
Y-368658D01*
X1626317Y-368742D01*
G01X1631417Y-368575D02*
Y-363575D01*
X1630657Y-364575D01*
G01Y-368575D02*
X1632177D01*
G01X1636390D02*
X1636517Y-367492D01*
X1636707Y-366575D01*
X1636960Y-365742D01*
X1637277Y-364825D01*
X1637784Y-363575D01*
X1635250D01*
G01X1640224Y-367825D02*
X1640604Y-368242D01*
X1641047Y-368492D01*
X1641617Y-368575D01*
X1642187Y-368408D01*
X1642630Y-368075D01*
X1642947Y-367492D01*
X1643010Y-366825D01*
X1642884Y-366158D01*
X1642567Y-365742D01*
X1642124Y-365408D01*
X1641680Y-365325D01*
X1641237Y-365408D01*
X1640667Y-365742D01*
X1640857Y-363575D01*
X1642567D01*
G01X1644817Y-368575D02*
Y-365242D01*
G01Y-366158D02*
X1645007Y-365742D01*
X1645324Y-365408D01*
X1645767Y-365242D01*
X1646210Y-365408D01*
X1646527Y-365742D01*
X1646717Y-366158D01*
Y-368575D01*
G01Y-366158D02*
X1646907Y-365742D01*
X1647224Y-365408D01*
X1647667Y-365242D01*
X1648110Y-365408D01*
X1648427Y-365742D01*
X1648617Y-366242D01*
Y-368575D01*
G01X1649917D02*
Y-365242D01*
G01Y-366158D02*
X1650107Y-365742D01*
X1650424Y-365408D01*
X1650867Y-365242D01*
X1651310Y-365408D01*
X1651627Y-365742D01*
X1651817Y-366158D01*
Y-368575D01*
G01Y-366158D02*
X1652007Y-365742D01*
X1652324Y-365408D01*
X1652767Y-365242D01*
X1653210Y-365408D01*
X1653527Y-365742D01*
X1653717Y-366242D01*
Y-368575D01*
G01X1660560D02*
Y-363575D01*
X1663474Y-368575D01*
Y-363575D01*
G01X1665850Y-368575D02*
Y-363575D01*
X1667370D01*
X1667877Y-363825D01*
X1668257Y-364408D01*
X1668384Y-365075D01*
X1668257Y-365742D01*
X1667940Y-366242D01*
X1667370Y-366492D01*
X1665850D01*
G01X1672217Y-363575D02*
Y-368575D01*
G01X1670760Y-363575D02*
X1673674D01*
G01X1675987Y-368575D02*
Y-363575D01*
G01X1678647D02*
Y-368575D01*
G01Y-366075D02*
X1675987D01*
G01X1522673Y-579227D02*
X1522173Y-578847D01*
X1521923Y-578404D01*
X1521840Y-577897D01*
X1522007Y-577264D01*
X1522423Y-576821D01*
X1522923Y-576694D01*
X1523423Y-576757D01*
X1523840Y-577011D01*
X1524673Y-578277D01*
X1525257Y-578847D01*
X1526090Y-579227D01*
X1526840Y-579354D01*
Y-576694D01*
G01X1543907Y-581961D02*
X1528946D01*
G01X1529340Y-578024D02*
Y-581961D01*
G01X1530324Y-587867D02*
X1529340Y-581961D01*
X1528355Y-587867D01*
X1530324D01*
G01X1543907Y-574087D02*
X1528946D01*
G01X1529340Y-578024D02*
Y-574087D01*
G01X1528355Y-568182D02*
X1529340Y-574087D01*
X1530324Y-568182D01*
X1528355D01*
G01X1531170Y-501347D02*
X1544633Y-522888D01*
G01X1543759Y-516772D02*
X1547999Y-514122D01*
X1546748Y-514008D01*
G01X1543356Y-516128D02*
X1544162Y-517417D01*
G01X1545358Y-510613D02*
G03I-2500J0D01*
G01X1547363Y-510746D02*
X1538353Y-510481D01*
G01X1535135Y-505833D02*
X1531170Y-501347D01*
X1533466Y-506876D01*
X1535135Y-505833D01*
G01X1542252Y-496505D02*
X1536719Y-498792D01*
X1542695Y-498423D01*
X1542252Y-496505D01*
G01X1536719Y-498792D02*
X1567048Y-491793D01*
G01X1542019Y-398767D02*
X1536465Y-401005D01*
X1542444Y-400689D01*
X1542019Y-398767D01*
G01X1536465Y-401005D02*
X1580568Y-391240D01*
G01X1563380Y-596178D02*
X1563760Y-596761D01*
X1564266Y-597095D01*
X1564836Y-597178D01*
X1565343Y-597095D01*
X1565850Y-596678D01*
X1566166Y-596178D01*
X1566230Y-595678D01*
X1566103Y-595095D01*
X1565660Y-594678D01*
X1565216Y-594511D01*
X1564646D01*
G01X1565216D02*
X1565596Y-594261D01*
X1565913Y-593845D01*
X1566040Y-593345D01*
X1565913Y-592845D01*
X1565596Y-592428D01*
X1565026Y-592178D01*
X1564456Y-592261D01*
X1563886Y-592595D01*
G01X1558473Y-580386D02*
Y-600071D01*
G01X1570284Y-580386D02*
Y-600071D01*
G01X1564773Y-599678D02*
X1558473D01*
G01X1552568Y-600662D02*
X1558473Y-599678D01*
X1552568Y-598693D01*
Y-600662D01*
G01X1564773Y-599678D02*
X1570284D01*
G01X1576190Y-598693D02*
X1570284Y-599678D01*
X1576190Y-600662D01*
Y-598693D01*
G01X1559398Y-489967D02*
X1559899Y-490450D01*
X1560468Y-490661D01*
X1561042Y-490614D01*
X1561517Y-490418D01*
X1561917Y-489899D01*
X1562113Y-489340D01*
X1562062Y-488839D01*
X1561808Y-488299D01*
X1561282Y-487993D01*
X1560813Y-487930D01*
X1560257Y-488058D01*
G01X1560813Y-487930D02*
X1561127Y-487601D01*
X1561342Y-487124D01*
X1561353Y-486608D01*
X1561117Y-486149D01*
X1560715Y-485814D01*
X1560103Y-485699D01*
X1559566Y-485908D01*
X1559086Y-486361D01*
G01X1557365Y-489474D02*
G03I-2501J0D01*
G01X1556457Y-485258D02*
X1553272Y-493689D01*
G01X1553017Y-393755D02*
X1553514Y-394243D01*
X1554080Y-394458D01*
X1554655Y-394417D01*
X1555132Y-394226D01*
X1555536Y-393709D01*
X1555737Y-393153D01*
X1555691Y-392651D01*
X1555441Y-392109D01*
X1554918Y-391798D01*
X1554449Y-391731D01*
X1553893Y-391854D01*
G01X1554449Y-391731D02*
X1554766Y-391405D01*
X1554986Y-390929D01*
X1555001Y-390414D01*
X1554769Y-389953D01*
X1554370Y-389615D01*
X1553760Y-389494D01*
X1553221Y-389698D01*
X1552737Y-390147D01*
G01X1559608Y-393491D02*
X1559466Y-393437D01*
X1559430Y-393274D01*
X1559536Y-393166D01*
X1559678Y-393220D01*
X1559714Y-393382D01*
X1559608Y-393491D01*
G01X1564551Y-392226D02*
X1563470Y-387345D01*
X1562944Y-388485D01*
G01X1563809Y-392391D02*
X1565293Y-392062D01*
G01X1569406Y-391152D02*
X1569296Y-390067D01*
X1569283Y-389131D01*
X1569350Y-388262D01*
X1569462Y-387299D01*
X1569686Y-385969D01*
X1567213Y-386516D01*
G01X1572987Y-389591D02*
X1573448Y-389916D01*
X1573934Y-390064D01*
X1574509Y-390022D01*
X1575030Y-389736D01*
X1575390Y-389315D01*
X1575573Y-388677D01*
X1575491Y-388013D01*
X1575223Y-387389D01*
X1574824Y-387051D01*
X1574319Y-386821D01*
X1573868Y-386836D01*
X1573454Y-387013D01*
X1572969Y-387461D01*
X1572686Y-385305D01*
X1574356Y-384935D01*
G01X1550987Y-393222D02*
G03I-2500J0D01*
G01X1550118Y-389020D02*
X1546857Y-397423D01*
G01X1678791Y-644166D02*
Y-639166D01*
X1680311D01*
X1680818Y-639416D01*
X1681198Y-639999D01*
X1681325Y-640666D01*
X1681198Y-641333D01*
X1680881Y-641833D01*
X1680311Y-642083D01*
X1678791D01*
G01X1686298Y-644166D02*
Y-640833D01*
G01Y-641416D02*
X1686045Y-641083D01*
X1685665Y-640916D01*
X1685221Y-640833D01*
X1684778Y-640999D01*
X1684398Y-641333D01*
X1684145Y-641833D01*
X1684018Y-642499D01*
X1684145Y-643166D01*
X1684398Y-643666D01*
X1684778Y-643999D01*
X1685221Y-644166D01*
X1685665Y-644083D01*
X1686045Y-643833D01*
X1686298Y-643499D01*
G01X1689181Y-644166D02*
Y-640833D01*
G01Y-641666D02*
X1689435Y-641249D01*
X1689815Y-640916D01*
X1690321Y-640833D01*
X1690765Y-640916D01*
X1691145Y-641249D01*
X1691335Y-641833D01*
Y-644166D01*
G01X1694408Y-641916D02*
X1696435D01*
X1696245Y-641333D01*
X1695928Y-640999D01*
X1695485Y-640833D01*
X1695041Y-640916D01*
X1694661Y-641166D01*
X1694408Y-641749D01*
X1694281Y-642249D01*
Y-642749D01*
X1694408Y-643249D01*
X1694725Y-643749D01*
X1695105Y-644083D01*
X1695548Y-644166D01*
X1695991Y-643999D01*
X1696435Y-643499D01*
G01X1700458Y-644166D02*
Y-639166D01*
G01X1709391Y-644166D02*
Y-639166D01*
X1710975D01*
X1711481Y-639416D01*
X1711798Y-639749D01*
X1711925Y-640416D01*
X1711798Y-641083D01*
X1711418Y-641499D01*
X1710975Y-641749D01*
X1709391D01*
G01X1710975D02*
X1711925Y-644166D01*
G01X1714808Y-641916D02*
X1716835D01*
X1716645Y-641333D01*
X1716328Y-640999D01*
X1715885Y-640833D01*
X1715441Y-640916D01*
X1715061Y-641166D01*
X1714808Y-641749D01*
X1714681Y-642249D01*
Y-642749D01*
X1714808Y-643249D01*
X1715125Y-643749D01*
X1715505Y-644083D01*
X1715948Y-644166D01*
X1716391Y-643999D01*
X1716835Y-643499D01*
G01X1719718Y-640833D02*
X1720858Y-644166D01*
X1721998Y-640833D01*
G01X1731565Y-641499D02*
X1731818Y-641249D01*
X1732008Y-640833D01*
X1732135Y-640249D01*
X1732008Y-639749D01*
X1731755Y-639416D01*
X1731311Y-639166D01*
X1729601D01*
Y-644166D01*
X1731691D01*
X1732135Y-643833D01*
X1732388Y-643333D01*
X1732515Y-642749D01*
X1732388Y-642166D01*
X1732008Y-641666D01*
X1731565Y-641499D01*
X1729601D01*
G01X-297025Y-1013390D02*
Y1828909D01*
X3691357D01*
Y-1013390D01*
X-297025D01*
G01X16913Y-817022D02*
X18480D01*
Y-818912D01*
X18010Y-819542D01*
X17461Y-819962D01*
X16678Y-820172D01*
X15895Y-819962D01*
X15346Y-819542D01*
X14876Y-818912D01*
X14563Y-818177D01*
X14406Y-817337D01*
Y-816602D01*
X14563Y-815972D01*
X14876Y-815237D01*
X15346Y-814607D01*
X15816Y-814187D01*
X16443Y-813872D01*
X16991D01*
X17618Y-814082D01*
X18088Y-814502D01*
G01X21020Y-813872D02*
Y-818387D01*
X21333Y-819332D01*
X21960Y-819962D01*
X22743Y-820172D01*
X23526Y-819962D01*
X24153Y-819332D01*
X24466Y-818387D01*
Y-813872D01*
G01X28103D02*
X29983D01*
G01X29043D02*
Y-820172D01*
G01X28103D02*
X29983D01*
G01X33698Y-819332D02*
X34325Y-819857D01*
X35030Y-820172D01*
X35656D01*
X36283Y-819857D01*
X36753Y-819332D01*
X36988Y-818597D01*
X36831Y-817862D01*
X36440Y-817232D01*
X35735Y-816812D01*
X34795Y-816602D01*
X34246Y-816182D01*
X34011Y-815447D01*
X34168Y-814712D01*
X34560Y-814187D01*
X35108Y-813872D01*
X35656D01*
X36205Y-814082D01*
X36675Y-814607D01*
G01X39998Y-820172D02*
Y-813872D01*
G01X43288D02*
Y-820172D01*
G01Y-817022D02*
X39998D01*
G01X45985Y-820172D02*
X47943Y-813872D01*
X49901Y-820172D01*
G01X49196Y-817967D02*
X46690D01*
G01X52441Y-820172D02*
Y-813872D01*
X56045Y-820172D01*
Y-813872D01*
G01X65120Y-820172D02*
Y-813872D01*
X66686D01*
X67313Y-814187D01*
X67783Y-814607D01*
X68175Y-815237D01*
X68488Y-815972D01*
X68566Y-817022D01*
X68488Y-818072D01*
X68175Y-818807D01*
X67783Y-819437D01*
X67313Y-819857D01*
X66686Y-820172D01*
X65120D01*
G01X72203Y-813872D02*
X74083D01*
G01X73143D02*
Y-820172D01*
G01X72203D02*
X74083D01*
G01X77798Y-819332D02*
X78425Y-819857D01*
X79130Y-820172D01*
X79756D01*
X80383Y-819857D01*
X80853Y-819332D01*
X81088Y-818597D01*
X80931Y-817862D01*
X80540Y-817232D01*
X79835Y-816812D01*
X78895Y-816602D01*
X78346Y-816182D01*
X78111Y-815447D01*
X78268Y-814712D01*
X78660Y-814187D01*
X79208Y-813872D01*
X79756D01*
X80305Y-814082D01*
X80775Y-814607D01*
G01X85743Y-813872D02*
Y-820172D01*
G01X83941Y-813872D02*
X87545D01*
G01X92043Y-820382D02*
X91886Y-820277D01*
Y-820067D01*
X92043Y-819962D01*
X92200Y-820067D01*
Y-820277D01*
X92043Y-820382D01*
G01X98186Y-821327D02*
X98500Y-819962D01*
G01X104643Y-813872D02*
Y-820172D01*
G01X102841Y-813872D02*
X106445D01*
G01X108985Y-820172D02*
X110943Y-813872D01*
X112901Y-820172D01*
G01X112196Y-817967D02*
X109690D01*
G01X117243Y-820172D02*
X116616Y-820067D01*
X116068Y-819647D01*
X115598Y-819017D01*
X115285Y-818282D01*
X115128Y-817442D01*
Y-816602D01*
X115285Y-815762D01*
X115598Y-815027D01*
X116068Y-814397D01*
X116616Y-813977D01*
X117243Y-813872D01*
X117870Y-813977D01*
X118418Y-814397D01*
X118888Y-815027D01*
X119201Y-815762D01*
X119358Y-816602D01*
Y-817442D01*
X119201Y-818282D01*
X118888Y-819017D01*
X118418Y-819647D01*
X117870Y-820067D01*
X117243Y-820172D01*
G01X123543D02*
Y-817337D01*
X121976Y-813872D01*
G01X125110D02*
X123543Y-817337D01*
G01X128120Y-813872D02*
Y-818387D01*
X128433Y-819332D01*
X129060Y-819962D01*
X129843Y-820172D01*
X130626Y-819962D01*
X131253Y-819332D01*
X131566Y-818387D01*
Y-813872D01*
G01X134185Y-820172D02*
X136143Y-813872D01*
X138101Y-820172D01*
G01X137396Y-817967D02*
X134890D01*
G01X140641Y-820172D02*
Y-813872D01*
X144245Y-820172D01*
Y-813872D01*
G01X18166Y-824397D02*
X17696Y-824082D01*
X17148Y-823872D01*
X16521D01*
X15816Y-824187D01*
X15268Y-824712D01*
X14876Y-825342D01*
X14563Y-826392D01*
X14485Y-827337D01*
X14641Y-828282D01*
X14876Y-828912D01*
X15346Y-829542D01*
X15895Y-829962D01*
X16443Y-830172D01*
X16991D01*
X17540Y-829962D01*
X18010Y-829647D01*
X18401Y-829227D01*
G01X21803Y-823872D02*
X23683D01*
G01X22743D02*
Y-830172D01*
G01X21803D02*
X23683D01*
G01X29043Y-823872D02*
Y-830172D01*
G01X27241Y-823872D02*
X30845D01*
G01X35343Y-830172D02*
Y-827337D01*
X33776Y-823872D01*
G01X36910D02*
X35343Y-827337D01*
G01X46220Y-828912D02*
X46690Y-829647D01*
X47316Y-830067D01*
X48021Y-830172D01*
X48648Y-830067D01*
X49275Y-829542D01*
X49666Y-828912D01*
X49745Y-828282D01*
X49588Y-827547D01*
X49040Y-827022D01*
X48491Y-826812D01*
X47786D01*
G01X48491D02*
X48961Y-826497D01*
X49353Y-825972D01*
X49510Y-825342D01*
X49353Y-824712D01*
X48961Y-824187D01*
X48256Y-823872D01*
X47551Y-823977D01*
X46846Y-824397D01*
G01X52520Y-828912D02*
X52990Y-829647D01*
X53616Y-830067D01*
X54321Y-830172D01*
X54948Y-830067D01*
X55575Y-829542D01*
X55966Y-828912D01*
X56045Y-828282D01*
X55888Y-827547D01*
X55340Y-827022D01*
X54791Y-826812D01*
X54086D01*
G01X54791D02*
X55261Y-826497D01*
X55653Y-825972D01*
X55810Y-825342D01*
X55653Y-824712D01*
X55261Y-824187D01*
X54556Y-823872D01*
X53851Y-823977D01*
X53146Y-824397D01*
G01X58820Y-828912D02*
X59290Y-829647D01*
X59916Y-830067D01*
X60621Y-830172D01*
X61248Y-830067D01*
X61875Y-829542D01*
X62266Y-828912D01*
X62345Y-828282D01*
X62188Y-827547D01*
X61640Y-827022D01*
X61091Y-826812D01*
X60386D01*
G01X61091D02*
X61561Y-826497D01*
X61953Y-825972D01*
X62110Y-825342D01*
X61953Y-824712D01*
X61561Y-824187D01*
X60856Y-823872D01*
X60151Y-823977D01*
X59446Y-824397D01*
G01X66686Y-830172D02*
X66843Y-828807D01*
X67078Y-827652D01*
X67391Y-826602D01*
X67783Y-825447D01*
X68410Y-823872D01*
X65276D01*
G01X72986Y-830172D02*
X73143Y-828807D01*
X73378Y-827652D01*
X73691Y-826602D01*
X74083Y-825447D01*
X74710Y-823872D01*
X71576D01*
G01X79286Y-831327D02*
X79600Y-829962D01*
G01X85743Y-823872D02*
Y-830172D01*
G01X83941Y-823872D02*
X87545D01*
G01X90085Y-830172D02*
X92043Y-823872D01*
X94001Y-830172D01*
G01X93296Y-827967D02*
X90790D01*
G01X97403Y-823872D02*
X99283D01*
G01X98343D02*
Y-830172D01*
G01X97403D02*
X99283D01*
G01X102293Y-823872D02*
X103390Y-830172D01*
X104643Y-823872D01*
X105896Y-830172D01*
X106993Y-823872D01*
G01X108985Y-830172D02*
X110943Y-823872D01*
X112901Y-830172D01*
G01X112196Y-827967D02*
X109690D01*
G01X115441Y-830172D02*
Y-823872D01*
X119045Y-830172D01*
Y-823872D01*
G01X129451Y-832272D02*
X128668Y-831222D01*
X128276Y-830172D01*
Y-825972D01*
X128668Y-824922D01*
X129451Y-823872D01*
G01X140876Y-830172D02*
Y-823872D01*
X142835D01*
X143461Y-824187D01*
X143853Y-824607D01*
X144010Y-825447D01*
X143853Y-826287D01*
X143383Y-826812D01*
X142835Y-827127D01*
X140876D01*
G01X142835D02*
X144010Y-830172D01*
G01X148743Y-830382D02*
X148586Y-830277D01*
Y-830067D01*
X148743Y-829962D01*
X148900Y-830067D01*
Y-830277D01*
X148743Y-830382D01*
G01X155043Y-830172D02*
X154416Y-830067D01*
X153868Y-829647D01*
X153398Y-829017D01*
X153085Y-828282D01*
X152928Y-827442D01*
Y-826602D01*
X153085Y-825762D01*
X153398Y-825027D01*
X153868Y-824397D01*
X154416Y-823977D01*
X155043Y-823872D01*
X155670Y-823977D01*
X156218Y-824397D01*
X156688Y-825027D01*
X157001Y-825762D01*
X157158Y-826602D01*
Y-827442D01*
X157001Y-828282D01*
X156688Y-829017D01*
X156218Y-829647D01*
X155670Y-830067D01*
X155043Y-830172D01*
G01X161343Y-830382D02*
X161186Y-830277D01*
Y-830067D01*
X161343Y-829962D01*
X161500Y-830067D01*
Y-830277D01*
X161343Y-830382D01*
G01X169366Y-824397D02*
X168896Y-824082D01*
X168348Y-823872D01*
X167721D01*
X167016Y-824187D01*
X166468Y-824712D01*
X166076Y-825342D01*
X165763Y-826392D01*
X165685Y-827337D01*
X165841Y-828282D01*
X166076Y-828912D01*
X166546Y-829542D01*
X167095Y-829962D01*
X167643Y-830172D01*
X168191D01*
X168740Y-829962D01*
X169210Y-829647D01*
X169601Y-829227D01*
G01X173943Y-830382D02*
X173786Y-830277D01*
Y-830067D01*
X173943Y-829962D01*
X174100Y-830067D01*
Y-830277D01*
X173943Y-830382D01*
G01X180635Y-832272D02*
X181418Y-831222D01*
X181810Y-830172D01*
Y-825972D01*
X181418Y-824922D01*
X180635Y-823872D01*
G01X38743Y-799472D02*
X36223Y-799055D01*
X34018Y-797389D01*
X32128Y-794889D01*
X30868Y-791972D01*
X30238Y-788639D01*
Y-785305D01*
X30868Y-781972D01*
X32128Y-779055D01*
X34018Y-776556D01*
X36223Y-774889D01*
X38743Y-774472D01*
X41263Y-774889D01*
X43468Y-776556D01*
X45358Y-779055D01*
X46618Y-781972D01*
X47248Y-785305D01*
Y-788639D01*
X46618Y-791972D01*
X45358Y-794889D01*
X43468Y-797389D01*
X41263Y-799055D01*
X38743Y-799472D01*
G01X41263Y-792805D02*
X45043Y-799472D01*
G01X58588Y-782806D02*
Y-794472D01*
X59848Y-797389D01*
X61738Y-799055D01*
X63943Y-799472D01*
X66148Y-799055D01*
X68038Y-797389D01*
X69298Y-794472D01*
G01Y-799472D02*
Y-782806D01*
G01X94813Y-799472D02*
Y-782806D01*
G01Y-785722D02*
X93553Y-784056D01*
X91663Y-783222D01*
X89458Y-782806D01*
X87253Y-783639D01*
X85363Y-785305D01*
X84103Y-787806D01*
X83473Y-791139D01*
X84103Y-794472D01*
X85363Y-796973D01*
X87253Y-798639D01*
X89458Y-799472D01*
X91663Y-799055D01*
X93553Y-797806D01*
X94813Y-796139D01*
G01X108988Y-799472D02*
Y-782806D01*
G01Y-786972D02*
X110248Y-784889D01*
X112138Y-783222D01*
X114658Y-782806D01*
X116863Y-783222D01*
X118753Y-784889D01*
X119698Y-787806D01*
Y-799472D01*
G01X139543Y-774472D02*
Y-799472D01*
G01X135133Y-782806D02*
X143953D01*
G01X170413Y-799472D02*
Y-782806D01*
G01Y-785722D02*
X169153Y-784056D01*
X167263Y-783222D01*
X165058Y-782806D01*
X162853Y-783639D01*
X160963Y-785305D01*
X159703Y-787806D01*
X159073Y-791139D01*
X159703Y-794472D01*
X160963Y-796973D01*
X162853Y-798639D01*
X165058Y-799472D01*
X167263Y-799055D01*
X169153Y-797806D01*
X170413Y-796139D01*
G01X14641Y-810172D02*
Y-803872D01*
X18245Y-810172D01*
Y-803872D01*
G01X22743Y-810172D02*
X22116Y-810067D01*
X21568Y-809647D01*
X21098Y-809017D01*
X20785Y-808282D01*
X20628Y-807442D01*
Y-806602D01*
X20785Y-805762D01*
X21098Y-805027D01*
X21568Y-804397D01*
X22116Y-803977D01*
X22743Y-803872D01*
X23370Y-803977D01*
X23918Y-804397D01*
X24388Y-805027D01*
X24701Y-805762D01*
X24858Y-806602D01*
Y-807442D01*
X24701Y-808282D01*
X24388Y-809017D01*
X23918Y-809647D01*
X23370Y-810067D01*
X22743Y-810172D01*
G01X29043Y-810382D02*
X28886Y-810277D01*
Y-810067D01*
X29043Y-809962D01*
X29200Y-810067D01*
Y-810277D01*
X29043Y-810382D01*
G01X33855Y-804922D02*
X34325Y-804292D01*
X34873Y-803977D01*
X35500Y-803872D01*
X36283Y-804082D01*
X36831Y-804607D01*
X36988Y-805237D01*
X36910Y-805867D01*
X36596Y-806392D01*
X35030Y-807442D01*
X34325Y-808177D01*
X33855Y-809227D01*
X33698Y-810172D01*
X36988D01*
G01X41643D02*
Y-803872D01*
X40703Y-805132D01*
G01Y-810172D02*
X42583D01*
G01X47943D02*
Y-803872D01*
X47003Y-805132D01*
G01Y-810172D02*
X48883D01*
G01X54086Y-811327D02*
X54400Y-809962D01*
G01X58193Y-803872D02*
X59290Y-810172D01*
X60543Y-803872D01*
X61796Y-810172D01*
X62893Y-803872D01*
G01X68410Y-810172D02*
X65276D01*
Y-803872D01*
X68410D01*
G01X67156Y-806917D02*
X65276D01*
G01X71341Y-810172D02*
Y-803872D01*
X74945Y-810172D01*
Y-803872D01*
G01X77798Y-810172D02*
Y-803872D01*
G01X81088D02*
Y-810172D01*
G01Y-807022D02*
X77798D01*
G01X84020Y-803872D02*
Y-808387D01*
X84333Y-809332D01*
X84960Y-809962D01*
X85743Y-810172D01*
X86526Y-809962D01*
X87153Y-809332D01*
X87466Y-808387D01*
Y-803872D01*
G01X90085Y-810172D02*
X92043Y-803872D01*
X94001Y-810172D01*
G01X93296Y-807967D02*
X90790D01*
G01X103155Y-804922D02*
X103625Y-804292D01*
X104173Y-803977D01*
X104800Y-803872D01*
X105583Y-804082D01*
X106131Y-804607D01*
X106288Y-805237D01*
X106210Y-805867D01*
X105896Y-806392D01*
X104330Y-807442D01*
X103625Y-808177D01*
X103155Y-809227D01*
X102998Y-810172D01*
X106288D01*
G01X109141D02*
Y-803872D01*
X112745Y-810172D01*
Y-803872D01*
G01X115520Y-810172D02*
Y-803872D01*
X117086D01*
X117713Y-804187D01*
X118183Y-804607D01*
X118575Y-805237D01*
X118888Y-805972D01*
X118966Y-807022D01*
X118888Y-808072D01*
X118575Y-808807D01*
X118183Y-809437D01*
X117713Y-809857D01*
X117086Y-810172D01*
X115520D01*
G01X128276D02*
Y-803872D01*
X130235D01*
X130861Y-804187D01*
X131253Y-804607D01*
X131410Y-805447D01*
X131253Y-806287D01*
X130783Y-806812D01*
X130235Y-807127D01*
X128276D01*
G01X130235D02*
X131410Y-810172D01*
G01X134420D02*
Y-803872D01*
X135986D01*
X136613Y-804187D01*
X137083Y-804607D01*
X137475Y-805237D01*
X137788Y-805972D01*
X137866Y-807022D01*
X137788Y-808072D01*
X137475Y-808807D01*
X137083Y-809437D01*
X136613Y-809857D01*
X135986Y-810172D01*
X134420D01*
G01X142443Y-810382D02*
X142286Y-810277D01*
Y-810067D01*
X142443Y-809962D01*
X142600Y-810067D01*
Y-810277D01*
X142443Y-810382D01*
G01X25935Y-614173D02*
G03I-6250J0D01*
G01Y636929D02*
G03I-6250J0D01*
G01X72835Y-614173D02*
G03I-5906J0D01*
G01X121792Y630884D02*
X126472D01*
G01X124132D02*
Y615284D01*
G01X121792D02*
X126472D01*
G01X137937Y617364D02*
X139497Y616064D01*
X141252Y615284D01*
X142812D01*
X144372Y616064D01*
X145542Y617364D01*
X146127Y619184D01*
X145737Y621004D01*
X144762Y622564D01*
X143007Y623604D01*
X140667Y624124D01*
X139302Y625164D01*
X138717Y626984D01*
X139107Y628804D01*
X140082Y630104D01*
X141447Y630884D01*
X142812D01*
X144177Y630364D01*
X145347Y629064D01*
G01X159932Y630884D02*
Y615284D01*
G01X155447Y630884D02*
X164417D01*
G01X196902Y623084D02*
X200802D01*
Y618404D01*
X199632Y616844D01*
X198267Y615804D01*
X196317Y615284D01*
X194367Y615804D01*
X193002Y616844D01*
X191832Y618404D01*
X191052Y620224D01*
X190662Y622304D01*
Y624124D01*
X191052Y625684D01*
X191832Y627504D01*
X193002Y629064D01*
X194172Y630104D01*
X195732Y630884D01*
X197097D01*
X198657Y630364D01*
X199827Y629324D01*
G01X217532Y615284D02*
X209732D01*
Y630884D01*
X217532D01*
G01X214412Y623344D02*
X209732D01*
G01X227632Y615284D02*
Y630884D01*
X232507D01*
X234067Y630104D01*
X235042Y629064D01*
X235432Y626984D01*
X235042Y624904D01*
X233872Y623604D01*
X232507Y622824D01*
X227632D01*
G01X232507D02*
X235432Y615284D01*
G01X250992Y623604D02*
X251772Y624384D01*
X252357Y625684D01*
X252747Y627504D01*
X252357Y629064D01*
X251577Y630104D01*
X250212Y630884D01*
X244947D01*
Y615284D01*
X251382D01*
X252747Y616324D01*
X253527Y617884D01*
X253917Y619704D01*
X253527Y621524D01*
X252357Y623084D01*
X250992Y623604D01*
X244947D01*
G01X271232Y615284D02*
X263432D01*
Y630884D01*
X271232D01*
G01X268112Y623344D02*
X263432D01*
G01X281332Y615284D02*
Y630884D01*
X286207D01*
X287767Y630104D01*
X288742Y629064D01*
X289132Y626984D01*
X288742Y624904D01*
X287572Y623604D01*
X286207Y622824D01*
X281332D01*
G01X286207D02*
X289132Y615284D01*
G01X302157Y610084D02*
X300207Y612684D01*
X299232Y615284D01*
Y625684D01*
X300207Y628284D01*
X302157Y630884D01*
G01X321032D02*
Y615284D01*
G01X316547Y630884D02*
X325517D01*
G01X334057D02*
X338932Y615284D01*
X343807Y630884D01*
G01X352737Y615284D02*
X360927Y630884D01*
G01X352737D02*
X360927Y615284D01*
G01X374732D02*
Y630884D01*
X372392Y627764D01*
G01Y615284D02*
X377072D01*
G01X392632Y630884D02*
X391072Y630364D01*
X389902Y629064D01*
X389122Y627504D01*
X388537Y625424D01*
X388342Y623084D01*
X388537Y620744D01*
X389122Y618664D01*
X389902Y617104D01*
X391072Y615804D01*
X392632Y615284D01*
X394192Y615804D01*
X395362Y617104D01*
X396142Y618664D01*
X396727Y620744D01*
X396922Y623084D01*
X396727Y625424D01*
X396142Y627504D01*
X395362Y629064D01*
X394192Y630364D01*
X392632Y630884D01*
G01X406242Y618404D02*
X407412Y616584D01*
X408972Y615544D01*
X410727Y615284D01*
X412287Y615544D01*
X413847Y616844D01*
X414822Y618404D01*
X415017Y619964D01*
X414627Y621784D01*
X413262Y623084D01*
X411897Y623604D01*
X410142D01*
G01X411897D02*
X413067Y624384D01*
X414042Y625684D01*
X414432Y627244D01*
X414042Y628804D01*
X413067Y630104D01*
X411312Y630884D01*
X409557Y630624D01*
X407802Y629584D01*
G01X424727Y621784D02*
X426092Y623604D01*
X427262Y624644D01*
X428822Y625164D01*
X430187Y624644D01*
X431162Y623604D01*
X431942Y622044D01*
X432137Y620224D01*
X431942Y618664D01*
X431162Y617104D01*
X429992Y615804D01*
X428627Y615284D01*
X427067Y615804D01*
X425702Y617364D01*
X424922Y619704D01*
X424727Y622304D01*
X425117Y625684D01*
X425702Y627504D01*
X426677Y629324D01*
X428042Y630624D01*
X429407Y630884D01*
X430772Y630364D01*
X431747Y629064D01*
G01X445942Y615284D02*
X446332Y618664D01*
X446917Y621524D01*
X447697Y624124D01*
X448672Y626984D01*
X450232Y630884D01*
X442432D01*
G01X459357Y615284D02*
X464232Y630884D01*
X469107Y615284D01*
G01X467352Y620744D02*
X461112D01*
G01X483107Y610084D02*
X485057Y612684D01*
X486032Y615284D01*
Y625684D01*
X485057Y628284D01*
X483107Y630884D01*
G01X210093Y-779172D02*
Y-787172D01*
X214093D01*
G01X221893D02*
Y-781839D01*
G01Y-782772D02*
X221493Y-782239D01*
X220893Y-781972D01*
X220193Y-781839D01*
X219493Y-782105D01*
X218893Y-782639D01*
X218493Y-783439D01*
X218293Y-784505D01*
X218493Y-785572D01*
X218893Y-786372D01*
X219493Y-786905D01*
X220193Y-787172D01*
X220893Y-787039D01*
X221493Y-786639D01*
X221893Y-786106D01*
G01X225993Y-789572D02*
X226593Y-789839D01*
X227393Y-789572D01*
X227893Y-789039D01*
X228293Y-788372D01*
X228893Y-786239D01*
X230193Y-781839D01*
G01X226993D02*
X228893Y-786239D01*
G01X234593Y-783572D02*
X237793D01*
X237493Y-782639D01*
X236993Y-782105D01*
X236293Y-781839D01*
X235593Y-781972D01*
X234993Y-782372D01*
X234593Y-783305D01*
X234393Y-784106D01*
Y-784905D01*
X234593Y-785705D01*
X235093Y-786505D01*
X235693Y-787039D01*
X236393Y-787172D01*
X237093Y-786905D01*
X237793Y-786106D01*
G01X242693Y-787172D02*
Y-781839D01*
G01Y-782905D02*
X243193Y-782372D01*
X243693Y-781972D01*
X244393Y-781839D01*
X244893Y-781972D01*
X245493Y-782372D01*
G01X229193Y-829172D02*
X232993D01*
X229193Y-837172D01*
X232993D01*
G01X239093Y-831839D02*
Y-837172D01*
G01Y-829705D02*
X238893Y-829572D01*
Y-829305D01*
X239093Y-829172D01*
X239293Y-829305D01*
Y-829572D01*
X239093Y-829705D01*
G01X245793Y-834505D02*
X248393D01*
G01X253093Y-837172D02*
Y-829172D01*
X255493D01*
X256293Y-829572D01*
X256893Y-830505D01*
X257093Y-831572D01*
X256893Y-832639D01*
X256393Y-833439D01*
X255493Y-833839D01*
X253093D01*
G01X263093Y-831839D02*
Y-837172D01*
G01Y-829705D02*
X262893Y-829572D01*
Y-829305D01*
X263093Y-829172D01*
X263293Y-829305D01*
Y-829572D01*
X263093Y-829705D01*
G01X269393Y-837172D02*
Y-831839D01*
G01Y-833172D02*
X269793Y-832505D01*
X270393Y-831972D01*
X271193Y-831839D01*
X271893Y-831972D01*
X272493Y-832505D01*
X272793Y-833439D01*
Y-837172D01*
G01X277693Y-839172D02*
X278393Y-839705D01*
X279193Y-839839D01*
X279893Y-839705D01*
X280493Y-839039D01*
X280893Y-838105D01*
Y-831839D01*
G01Y-832905D02*
X280493Y-832372D01*
X279893Y-831972D01*
X279193Y-831839D01*
X278393Y-832105D01*
X277893Y-832639D01*
X277493Y-833572D01*
X277293Y-834505D01*
X277393Y-835305D01*
X277793Y-836239D01*
X278393Y-836905D01*
X279193Y-837172D01*
X279793Y-837039D01*
X280493Y-836505D01*
X280893Y-835972D01*
G01X229093Y-812172D02*
Y-804172D01*
X231493D01*
X232293Y-804572D01*
X232893Y-805505D01*
X233093Y-806572D01*
X232893Y-807639D01*
X232393Y-808439D01*
X231493Y-808839D01*
X229093D01*
G01X236593Y-812172D02*
X239093Y-804172D01*
X241593Y-812172D01*
G01X240693Y-809372D02*
X237493D01*
G01X244793Y-812172D02*
Y-804172D01*
X249393Y-812172D01*
Y-804172D01*
G01X257093Y-812172D02*
X253093D01*
Y-804172D01*
X257093D01*
G01X255493Y-808039D02*
X253093D01*
G01X261093Y-804172D02*
Y-812172D01*
X265093D01*
G01X336693Y-830505D02*
X337293Y-829705D01*
X337993Y-829305D01*
X338793Y-829172D01*
X339793Y-829439D01*
X340493Y-830105D01*
X340693Y-830905D01*
X340593Y-831706D01*
X340193Y-832372D01*
X338193Y-833705D01*
X337293Y-834639D01*
X336693Y-835972D01*
X336493Y-837172D01*
X340693D01*
G01X346593Y-829172D02*
X345793Y-829439D01*
X345193Y-830105D01*
X344793Y-830905D01*
X344493Y-831972D01*
X344393Y-833172D01*
X344493Y-834372D01*
X344793Y-835439D01*
X345193Y-836239D01*
X345793Y-836905D01*
X346593Y-837172D01*
X347393Y-836905D01*
X347993Y-836239D01*
X348393Y-835439D01*
X348693Y-834372D01*
X348793Y-833172D01*
X348693Y-831972D01*
X348393Y-830905D01*
X347993Y-830105D01*
X347393Y-829439D01*
X346593Y-829172D01*
G01X352693Y-830505D02*
X353293Y-829705D01*
X353993Y-829305D01*
X354793Y-829172D01*
X355793Y-829439D01*
X356493Y-830105D01*
X356693Y-830905D01*
X356593Y-831706D01*
X356193Y-832372D01*
X354193Y-833705D01*
X353293Y-834639D01*
X352693Y-835972D01*
X352493Y-837172D01*
X356693D01*
G01X360693Y-830505D02*
X361293Y-829705D01*
X361993Y-829305D01*
X362793Y-829172D01*
X363793Y-829439D01*
X364493Y-830105D01*
X364693Y-830905D01*
X364593Y-831706D01*
X364193Y-832372D01*
X362193Y-833705D01*
X361293Y-834639D01*
X360693Y-835972D01*
X360493Y-837172D01*
X364693D01*
G01X368793Y-837439D02*
X372393Y-829172D01*
G01X378593Y-837172D02*
Y-829172D01*
X377393Y-830772D01*
G01Y-837172D02*
X379793D01*
G01X384693Y-830505D02*
X385293Y-829705D01*
X385993Y-829305D01*
X386793Y-829172D01*
X387793Y-829439D01*
X388493Y-830105D01*
X388693Y-830905D01*
X388593Y-831706D01*
X388193Y-832372D01*
X386193Y-833705D01*
X385293Y-834639D01*
X384693Y-835972D01*
X384493Y-837172D01*
X388693D01*
G01X392793Y-837439D02*
X396393Y-829172D01*
G01X402593D02*
X401793Y-829439D01*
X401193Y-830105D01*
X400793Y-830905D01*
X400493Y-831972D01*
X400393Y-833172D01*
X400493Y-834372D01*
X400793Y-835439D01*
X401193Y-836239D01*
X401793Y-836905D01*
X402593Y-837172D01*
X403393Y-836905D01*
X403993Y-836239D01*
X404393Y-835439D01*
X404693Y-834372D01*
X404793Y-833172D01*
X404693Y-831972D01*
X404393Y-830905D01*
X403993Y-830105D01*
X403393Y-829439D01*
X402593Y-829172D01*
G01X408693Y-830505D02*
X409293Y-829705D01*
X409993Y-829305D01*
X410793Y-829172D01*
X411793Y-829439D01*
X412493Y-830105D01*
X412693Y-830905D01*
X412593Y-831706D01*
X412193Y-832372D01*
X410193Y-833705D01*
X409293Y-834639D01*
X408693Y-835972D01*
X408493Y-837172D01*
X412693D01*
G01X336393Y-814672D02*
Y-806672D01*
X338393D01*
X339193Y-807072D01*
X339793Y-807605D01*
X340293Y-808405D01*
X340693Y-809339D01*
X340793Y-810672D01*
X340693Y-812005D01*
X340293Y-812939D01*
X339793Y-813739D01*
X339193Y-814272D01*
X338393Y-814672D01*
X336393D01*
G01X344093D02*
X346593Y-806672D01*
X349093Y-814672D01*
G01X348193Y-811872D02*
X344993D01*
G01X354593Y-806672D02*
X353793Y-806939D01*
X353193Y-807605D01*
X352793Y-808405D01*
X352493Y-809472D01*
X352393Y-810672D01*
X352493Y-811872D01*
X352793Y-812939D01*
X353193Y-813739D01*
X353793Y-814405D01*
X354593Y-814672D01*
X355393Y-814405D01*
X355993Y-813739D01*
X356393Y-812939D01*
X356693Y-811872D01*
X356793Y-810672D01*
X356693Y-809472D01*
X356393Y-808405D01*
X355993Y-807605D01*
X355393Y-806939D01*
X354593Y-806672D01*
G01X360693Y-814672D02*
Y-806672D01*
X364493D01*
G01X363093Y-810539D02*
X360693D01*
G01X370593Y-806672D02*
X369793Y-806939D01*
X369193Y-807605D01*
X368793Y-808405D01*
X368493Y-809472D01*
X368393Y-810672D01*
X368493Y-811872D01*
X368793Y-812939D01*
X369193Y-813739D01*
X369793Y-814405D01*
X370593Y-814672D01*
X371393Y-814405D01*
X371993Y-813739D01*
X372393Y-812939D01*
X372693Y-811872D01*
X372793Y-810672D01*
X372693Y-809472D01*
X372393Y-808405D01*
X371993Y-807605D01*
X371393Y-806939D01*
X370593Y-806672D01*
G01X378593D02*
Y-814672D01*
G01X376293Y-806672D02*
X380893D01*
G01X384593Y-814672D02*
Y-806672D01*
X386993D01*
X387793Y-807072D01*
X388393Y-808005D01*
X388593Y-809072D01*
X388393Y-810139D01*
X387893Y-810939D01*
X386993Y-811339D01*
X384593D01*
G01X395393Y-810405D02*
X395793Y-810005D01*
X396093Y-809339D01*
X396293Y-808405D01*
X396093Y-807605D01*
X395693Y-807072D01*
X394993Y-806672D01*
X392293D01*
Y-814672D01*
X395593D01*
X396293Y-814139D01*
X396693Y-813339D01*
X396893Y-812405D01*
X396693Y-811472D01*
X396093Y-810672D01*
X395393Y-810405D01*
X392293D01*
G01X400093Y-814672D02*
X402593Y-806672D01*
X405093Y-814672D01*
G01X404193Y-811872D02*
X400993D01*
G01X408693Y-814672D02*
Y-806672D01*
X412493D01*
G01X411093Y-810539D02*
X408693D01*
G01X418593Y-806672D02*
X417793Y-806939D01*
X417193Y-807605D01*
X416793Y-808405D01*
X416493Y-809472D01*
X416393Y-810672D01*
X416493Y-811872D01*
X416793Y-812939D01*
X417193Y-813739D01*
X417793Y-814405D01*
X418593Y-814672D01*
X419393Y-814405D01*
X419993Y-813739D01*
X420393Y-812939D01*
X420693Y-811872D01*
X420793Y-810672D01*
X420693Y-809472D01*
X420393Y-808405D01*
X419993Y-807605D01*
X419393Y-806939D01*
X418593Y-806672D01*
G01X356693Y-787172D02*
Y-779172D01*
X360493D01*
G01X359093Y-783039D02*
X356693D01*
G01X366593Y-779172D02*
X365793Y-779439D01*
X365193Y-780105D01*
X364793Y-780905D01*
X364493Y-781972D01*
X364393Y-783172D01*
X364493Y-784372D01*
X364793Y-785439D01*
X365193Y-786239D01*
X365793Y-786905D01*
X366593Y-787172D01*
X367393Y-786905D01*
X367993Y-786239D01*
X368393Y-785439D01*
X368693Y-784372D01*
X368793Y-783172D01*
X368693Y-781972D01*
X368393Y-780905D01*
X367993Y-780105D01*
X367393Y-779439D01*
X366593Y-779172D01*
G01X374593D02*
Y-787172D01*
G01X372293Y-779172D02*
X376893D01*
G01X379593Y-789839D02*
X385593D01*
G01X388593Y-787172D02*
Y-779172D01*
X390993D01*
X391793Y-779572D01*
X392393Y-780505D01*
X392593Y-781572D01*
X392393Y-782639D01*
X391893Y-783439D01*
X390993Y-783839D01*
X388593D01*
G01X396393Y-787172D02*
Y-779172D01*
X398393D01*
X399193Y-779572D01*
X399793Y-780105D01*
X400293Y-780905D01*
X400693Y-781839D01*
X400793Y-783172D01*
X400693Y-784505D01*
X400293Y-785439D01*
X399793Y-786239D01*
X399193Y-786772D01*
X398393Y-787172D01*
X396393D01*
G01X407393Y-782905D02*
X407793Y-782505D01*
X408093Y-781839D01*
X408293Y-780905D01*
X408093Y-780105D01*
X407693Y-779572D01*
X406993Y-779172D01*
X404293D01*
Y-787172D01*
X407593D01*
X408293Y-786639D01*
X408693Y-785839D01*
X408893Y-784905D01*
X408693Y-783972D01*
X408093Y-783172D01*
X407393Y-782905D01*
X404293D01*
G01X411593Y-789839D02*
X417593D01*
G01X424793Y-779839D02*
X424193Y-779439D01*
X423493Y-779172D01*
X422693D01*
X421793Y-779572D01*
X421093Y-780239D01*
X420593Y-781039D01*
X420193Y-782372D01*
X420093Y-783572D01*
X420293Y-784772D01*
X420593Y-785572D01*
X421193Y-786372D01*
X421893Y-786905D01*
X422593Y-787172D01*
X423293D01*
X423993Y-786905D01*
X424593Y-786505D01*
X425093Y-785972D01*
G01X430593Y-787172D02*
X429793Y-787039D01*
X429093Y-786505D01*
X428493Y-785705D01*
X428093Y-784772D01*
X427893Y-783705D01*
Y-782639D01*
X428093Y-781572D01*
X428493Y-780639D01*
X429093Y-779839D01*
X429793Y-779305D01*
X430593Y-779172D01*
X431393Y-779305D01*
X432093Y-779839D01*
X432693Y-780639D01*
X433093Y-781572D01*
X433293Y-782639D01*
Y-783705D01*
X433093Y-784772D01*
X432693Y-785705D01*
X432093Y-786505D01*
X431393Y-787039D01*
X430593Y-787172D01*
G01X436293D02*
Y-779172D01*
X440893Y-787172D01*
Y-779172D01*
G01X444093D02*
X446593Y-787172D01*
X449093Y-779172D01*
G01X456593Y-787172D02*
X452593D01*
Y-779172D01*
X456593D01*
G01X454993Y-783039D02*
X452593D01*
G01X460593Y-787172D02*
Y-779172D01*
X463093D01*
X463893Y-779572D01*
X464393Y-780105D01*
X464593Y-781172D01*
X464393Y-782239D01*
X463793Y-782905D01*
X463093Y-783305D01*
X460593D01*
G01X463093D02*
X464593Y-787172D01*
G01X470593Y-779172D02*
Y-787172D01*
G01X468293Y-779172D02*
X472893D01*
G01X480593Y-787172D02*
X476593D01*
Y-779172D01*
X480593D01*
G01X478993Y-783039D02*
X476593D01*
G01X484593Y-787172D02*
Y-779172D01*
X487093D01*
X487893Y-779572D01*
X488393Y-780105D01*
X488593Y-781172D01*
X488393Y-782239D01*
X487793Y-782905D01*
X487093Y-783305D01*
X484593D01*
G01X487093D02*
X488593Y-787172D01*
G01X425093Y-840172D02*
Y-832172D01*
X423893Y-833772D01*
G01Y-840172D02*
X426293D01*
G01X431193Y-836839D02*
X431893Y-835905D01*
X432493Y-835372D01*
X433293Y-835105D01*
X433993Y-835372D01*
X434493Y-835905D01*
X434893Y-836705D01*
X434993Y-837639D01*
X434893Y-838439D01*
X434493Y-839239D01*
X433893Y-839905D01*
X433193Y-840172D01*
X432393Y-839905D01*
X431693Y-839106D01*
X431293Y-837905D01*
X431193Y-836572D01*
X431393Y-834839D01*
X431693Y-833905D01*
X432193Y-832972D01*
X432893Y-832305D01*
X433593Y-832172D01*
X434293Y-832439D01*
X434793Y-833105D01*
G01X441093Y-840439D02*
X440893Y-840305D01*
Y-840039D01*
X441093Y-839905D01*
X441293Y-840039D01*
Y-840305D01*
X441093Y-840439D01*
G01X447193Y-836839D02*
X447893Y-835905D01*
X448493Y-835372D01*
X449293Y-835105D01*
X449993Y-835372D01*
X450493Y-835905D01*
X450893Y-836705D01*
X450993Y-837639D01*
X450893Y-838439D01*
X450493Y-839239D01*
X449893Y-839905D01*
X449193Y-840172D01*
X448393Y-839905D01*
X447693Y-839106D01*
X447293Y-837905D01*
X447193Y-836572D01*
X447393Y-834839D01*
X447693Y-833905D01*
X448193Y-832972D01*
X448893Y-832305D01*
X449593Y-832172D01*
X450293Y-832439D01*
X450793Y-833105D01*
G01X470093Y-840172D02*
Y-832172D01*
X468893Y-833772D01*
G01Y-840172D02*
X471293D01*
G01X477893D02*
X478093Y-838439D01*
X478393Y-836972D01*
X478793Y-835639D01*
X479293Y-834172D01*
X480093Y-832172D01*
X476093D01*
G01X486093Y-840439D02*
X485893Y-840305D01*
Y-840039D01*
X486093Y-839905D01*
X486293Y-840039D01*
Y-840305D01*
X486093Y-840439D01*
G01X492193Y-833505D02*
X492793Y-832705D01*
X493493Y-832305D01*
X494293Y-832172D01*
X495293Y-832439D01*
X495993Y-833105D01*
X496193Y-833905D01*
X496093Y-834706D01*
X495693Y-835372D01*
X493693Y-836705D01*
X492793Y-837639D01*
X492193Y-838972D01*
X491993Y-840172D01*
X496193D01*
G01X490193Y-815172D02*
Y-807172D01*
X493993D01*
G01X492593Y-811039D02*
X490193D01*
G01X544392Y630914D02*
X543222Y631694D01*
X541857Y632214D01*
X540297D01*
X538542Y631434D01*
X537177Y630134D01*
X536202Y628574D01*
X535422Y625974D01*
X535227Y623634D01*
X535617Y621294D01*
X536202Y619734D01*
X537372Y618174D01*
X538737Y617134D01*
X540102Y616614D01*
X541467D01*
X542832Y617134D01*
X544002Y617914D01*
X544977Y618954D01*
G01X559562Y624934D02*
X560342Y625714D01*
X560927Y627014D01*
X561317Y628834D01*
X560927Y630394D01*
X560147Y631434D01*
X558782Y632214D01*
X553517D01*
Y616614D01*
X559952D01*
X561317Y617654D01*
X562097Y619214D01*
X562487Y621034D01*
X562097Y622854D01*
X560927Y624414D01*
X559562Y624934D01*
X553517D01*
G01X602269Y702864D02*
Y715364D01*
X600409Y712864D01*
G01Y702864D02*
X604129D01*
G01X611724Y713281D02*
X612654Y714530D01*
X613739Y715156D01*
X614979Y715364D01*
X616529Y714947D01*
X617614Y713906D01*
X617924Y712656D01*
X617769Y711405D01*
X617149Y710364D01*
X614049Y708281D01*
X612654Y706822D01*
X611724Y704739D01*
X611414Y702864D01*
X617924D01*
G01X624434Y704322D02*
X625519Y703281D01*
X626759Y702864D01*
X627999Y703281D01*
X629084Y704530D01*
X629859Y706406D01*
X630169Y708281D01*
Y710572D01*
X629859Y712447D01*
X629084Y714114D01*
X628154Y714947D01*
X627069Y715364D01*
X625829Y714947D01*
X624899Y714114D01*
X624279Y712864D01*
X623969Y711197D01*
X624279Y709739D01*
X625054Y708281D01*
X625984Y707447D01*
X627069Y707239D01*
X628309Y707655D01*
X629239Y708697D01*
X630169Y710572D01*
G01X639469Y702864D02*
Y715364D01*
X637609Y712864D01*
G01Y702864D02*
X641329D01*
G01X648459Y705364D02*
X649389Y703905D01*
X650629Y703072D01*
X652024Y702864D01*
X653264Y703072D01*
X654504Y704114D01*
X655279Y705364D01*
X655434Y706614D01*
X655124Y708072D01*
X654039Y709114D01*
X652954Y709531D01*
X651559D01*
G01X652954D02*
X653884Y710156D01*
X654659Y711197D01*
X654969Y712447D01*
X654659Y713697D01*
X653884Y714739D01*
X652489Y715364D01*
X651094Y715156D01*
X649699Y714322D01*
G01X664269Y702447D02*
X663959Y702656D01*
Y703072D01*
X664269Y703281D01*
X664579Y703072D01*
Y702656D01*
X664269Y702447D01*
G01X673259Y705364D02*
X674189Y703905D01*
X675429Y703072D01*
X676824Y702864D01*
X678064Y703072D01*
X679304Y704114D01*
X680079Y705364D01*
X680234Y706614D01*
X679924Y708072D01*
X678839Y709114D01*
X677754Y709531D01*
X676359D01*
G01X677754D02*
X678684Y710156D01*
X679459Y711197D01*
X679769Y712447D01*
X679459Y713697D01*
X678684Y714739D01*
X677289Y715364D01*
X675894Y715156D01*
X674499Y714322D01*
G01X686434Y704322D02*
X687519Y703281D01*
X688759Y702864D01*
X689999Y703281D01*
X691084Y704530D01*
X691859Y706406D01*
X692169Y708281D01*
Y710572D01*
X691859Y712447D01*
X691084Y714114D01*
X690154Y714947D01*
X689069Y715364D01*
X687829Y714947D01*
X686899Y714114D01*
X686279Y712864D01*
X685969Y711197D01*
X686279Y709739D01*
X687054Y708281D01*
X687984Y707447D01*
X689069Y707239D01*
X690309Y707655D01*
X691239Y708697D01*
X692169Y710572D01*
G01X625935Y636929D02*
G03I-6250J0D01*
G01X630009Y680364D02*
X630939Y678905D01*
X632179Y678072D01*
X633574Y677864D01*
X634814Y678072D01*
X636054Y679114D01*
X636829Y680364D01*
X636984Y681614D01*
X636674Y683072D01*
X635589Y684114D01*
X634504Y684531D01*
X633109D01*
G01X634504D02*
X635434Y685156D01*
X636209Y686197D01*
X636519Y687447D01*
X636209Y688697D01*
X635434Y689739D01*
X634039Y690364D01*
X632644Y690156D01*
X631249Y689322D01*
G01X642874Y688281D02*
X643804Y689530D01*
X644889Y690156D01*
X646129Y690364D01*
X647679Y689947D01*
X648764Y688906D01*
X649074Y687656D01*
X648919Y686405D01*
X648299Y685364D01*
X645199Y683281D01*
X643804Y681822D01*
X642874Y679739D01*
X642564Y677864D01*
X649074D01*
G01X658219D02*
X659304Y678072D01*
X660544Y678697D01*
X661319Y679739D01*
X661629Y681197D01*
X661319Y682655D01*
X660389Y683906D01*
X658994Y684531D01*
X657444D01*
X656514Y684947D01*
X655739Y685989D01*
X655429Y687447D01*
X655894Y688906D01*
X656979Y689947D01*
X658219Y690364D01*
X659459Y689947D01*
X660544Y688906D01*
X661009Y687447D01*
X660699Y685989D01*
X659924Y684947D01*
X658994Y684531D01*
X657444D01*
X656049Y683906D01*
X655119Y682655D01*
X654809Y681197D01*
X655119Y679739D01*
X655894Y678697D01*
X657134Y678072D01*
X658219Y677864D01*
G01X1250000Y636929D02*
G03I-5905J0D01*
G01X1277904Y-614173D02*
G03I-6250J0D01*
G01Y636929D02*
G03I-6250J0D01*
G01X1303641Y753014D02*
X1306140Y752934D01*
X1306119Y752268D01*
X1305987Y752059D01*
X1305816Y751931D01*
X1305481Y751888D01*
X1305150Y751952D01*
X1304947Y752119D01*
X1304828Y752309D01*
X1304849Y752976D01*
G01X1304828Y752309D02*
X1303607Y751948D01*
G01X1305652Y750722D02*
X1305897Y750554D01*
X1306016Y750363D01*
X1306050Y750149D01*
X1305958Y749885D01*
X1305744Y749705D01*
X1305493Y749660D01*
X1305244Y749694D01*
X1305039Y749808D01*
X1304639Y750354D01*
X1304356Y750603D01*
X1303944Y750777D01*
X1303571Y750842D01*
X1303535Y749723D01*
G01X1303508Y748883D02*
X1305174Y748829D01*
G01X1304716Y748844D02*
X1304921Y748758D01*
X1305084Y748619D01*
X1305161Y748430D01*
X1305072Y748246D01*
X1304901Y748118D01*
X1304690Y748045D01*
X1303482Y748083D01*
G01X1304690Y748045D02*
X1304896Y747958D01*
X1305058Y747819D01*
X1305135Y747630D01*
X1305046Y747446D01*
X1304875Y747318D01*
X1304623Y747246D01*
X1303457Y747284D01*
G01X1303437Y746684D02*
X1305103Y746630D01*
G01X1304645Y746645D02*
X1304850Y746559D01*
X1305013Y746420D01*
X1305090Y746231D01*
X1305001Y746047D01*
X1304830Y745919D01*
X1304619Y745846D01*
X1303411Y745884D01*
G01X1304619Y745846D02*
X1304825Y745759D01*
X1304987Y745620D01*
X1305064Y745431D01*
X1304975Y745247D01*
X1304804Y745119D01*
X1304552Y745047D01*
X1303386Y745085D01*
G01X1292879Y755361D02*
X1293304Y755615D01*
X1293724Y755734D01*
X1295390Y755681D01*
X1295802Y755534D01*
X1296210Y755254D01*
G01X1293553Y753005D02*
X1293596Y753057D01*
X1293680Y753054D01*
X1293720Y753000D01*
X1293676Y752948D01*
X1293593Y752950D01*
X1293553Y753005D01*
G01X1296064Y750723D02*
X1295988Y750939D01*
X1295784Y751106D01*
X1295538Y751220D01*
X1295207Y751311D01*
X1294833Y751350D01*
X1294458Y751335D01*
X1294122Y751266D01*
X1293869Y751167D01*
X1293655Y751014D01*
X1293565Y750803D01*
X1293642Y750588D01*
X1293845Y750421D01*
X1294091Y750306D01*
X1294422Y750216D01*
X1294796Y750177D01*
X1295171Y750191D01*
X1295507Y750261D01*
X1295760Y750359D01*
X1295974Y750513D01*
X1296064Y750723D01*
G01X1293494Y748604D02*
X1293530Y748417D01*
X1293648Y748199D01*
X1293852Y748059D01*
X1294142Y747997D01*
X1294435Y748041D01*
X1294690Y748192D01*
X1294823Y748428D01*
X1294831Y748695D01*
X1294920Y748852D01*
X1295132Y748979D01*
X1295425Y749023D01*
X1295714Y748933D01*
X1295917Y748740D01*
X1295993Y748524D01*
X1295903Y748314D01*
X1295689Y748134D01*
X1295395Y748063D01*
X1295105Y748126D01*
X1294901Y748266D01*
X1294823Y748428D01*
X1294831Y748695D01*
X1294714Y748939D01*
X1294469Y749107D01*
X1294179Y749169D01*
X1293886Y749125D01*
X1293674Y748999D01*
X1293542Y748790D01*
X1293494Y748604D01*
G01X1295089Y746352D02*
X1293423Y746405D01*
G01X1295755Y746330D02*
X1295799Y746382D01*
X1295882Y746380D01*
X1295922Y746325D01*
X1295879Y746273D01*
X1295795Y746276D01*
X1295755Y746330D01*
G01X1293367Y744660D02*
X1295033Y744606D01*
G01X1294616Y744619D02*
X1294821Y744506D01*
X1294982Y744341D01*
X1295017Y744126D01*
X1294970Y743941D01*
X1294798Y743786D01*
X1294504Y743716D01*
X1293338Y743753D01*
G01X1294725Y741534D02*
X1294898Y741715D01*
X1294944Y741874D01*
X1294868Y742090D01*
X1294707Y742255D01*
X1294419Y742371D01*
X1294128Y742407D01*
X1293835Y742390D01*
X1293582Y742291D01*
X1293369Y742138D01*
X1293279Y741927D01*
X1293356Y741738D01*
X1293517Y741573D01*
G01X1293225Y740262D02*
X1295724Y740181D01*
G01X1294516Y740220D02*
X1294720Y740080D01*
X1294840Y739943D01*
X1294875Y739728D01*
X1294828Y739570D01*
X1294656Y739388D01*
X1294403Y739316D01*
X1293196Y739355D01*
G01X1292302Y737503D02*
X1292710Y737223D01*
X1293122Y737076D01*
X1294788Y737023D01*
X1295209Y737143D01*
X1295634Y737396D01*
G01X1325089Y-32022D02*
X1312589D01*
X1315089Y-33882D01*
G01X1325089D02*
Y-30162D01*
G01X1314672Y-22567D02*
X1313423Y-21637D01*
X1312797Y-20552D01*
X1312589Y-19312D01*
X1313006Y-17762D01*
X1314047Y-16677D01*
X1315297Y-16367D01*
X1316548Y-16522D01*
X1317589Y-17142D01*
X1319672Y-20242D01*
X1321131Y-21637D01*
X1323214Y-22567D01*
X1325089Y-22877D01*
Y-16367D01*
G01X1323631Y-9857D02*
X1324672Y-8772D01*
X1325089Y-7532D01*
X1324672Y-6292D01*
X1323423Y-5207D01*
X1321547Y-4432D01*
X1319672Y-4122D01*
X1317381D01*
X1315506Y-4432D01*
X1313839Y-5207D01*
X1313006Y-6137D01*
X1312589Y-7222D01*
X1313006Y-8462D01*
X1313839Y-9392D01*
X1315089Y-10012D01*
X1316756Y-10322D01*
X1318214Y-10012D01*
X1319672Y-9237D01*
X1320506Y-8307D01*
X1320714Y-7222D01*
X1320298Y-5982D01*
X1319256Y-5052D01*
X1317381Y-4122D01*
G01X1312589Y5178D02*
X1313006Y3938D01*
X1314047Y3008D01*
X1315297Y2388D01*
X1316964Y1923D01*
X1318839Y1768D01*
X1320714Y1923D01*
X1322381Y2388D01*
X1323631Y3008D01*
X1324672Y3938D01*
X1325089Y5178D01*
X1324672Y6418D01*
X1323631Y7348D01*
X1322381Y7968D01*
X1320714Y8433D01*
X1318839Y8588D01*
X1316964Y8433D01*
X1315297Y7968D01*
X1314047Y7348D01*
X1313006Y6418D01*
X1312589Y5178D01*
G01X1325089Y19438D02*
X1312589D01*
X1321547Y13703D01*
Y21453D01*
G01X1325506Y29978D02*
X1325297Y29668D01*
X1324881D01*
X1324672Y29978D01*
X1324881Y30288D01*
X1325297D01*
X1325506Y29978D01*
G01X1325089Y42068D02*
X1322381Y42378D01*
X1320089Y42843D01*
X1318006Y43463D01*
X1315714Y44238D01*
X1312589Y45478D01*
Y39278D01*
G01X1314672Y51833D02*
X1313423Y52763D01*
X1312797Y53848D01*
X1312589Y55088D01*
X1313006Y56638D01*
X1314047Y57723D01*
X1315297Y58033D01*
X1316548Y57878D01*
X1317589Y57258D01*
X1319672Y54158D01*
X1321131Y52763D01*
X1323214Y51833D01*
X1325089Y51523D01*
Y58033D01*
G01X1347589Y-22882D02*
X1349048Y-21952D01*
X1349881Y-20712D01*
X1350089Y-19317D01*
X1349881Y-18077D01*
X1348839Y-16837D01*
X1347589Y-16062D01*
X1346339Y-15907D01*
X1344881Y-16217D01*
X1343839Y-17302D01*
X1343422Y-18387D01*
Y-19782D01*
G01Y-18387D02*
X1342797Y-17457D01*
X1341756Y-16682D01*
X1340506Y-16372D01*
X1339256Y-16682D01*
X1338214Y-17457D01*
X1337589Y-18852D01*
X1337797Y-20247D01*
X1338631Y-21642D01*
G01X1339672Y-10017D02*
X1338423Y-9087D01*
X1337797Y-8002D01*
X1337589Y-6762D01*
X1338006Y-5212D01*
X1339047Y-4127D01*
X1340297Y-3817D01*
X1341548Y-3972D01*
X1342589Y-4592D01*
X1344672Y-7692D01*
X1346131Y-9087D01*
X1348214Y-10017D01*
X1350089Y-10327D01*
Y-3817D01*
G01Y5018D02*
X1347381Y5328D01*
X1345089Y5793D01*
X1343006Y6413D01*
X1340714Y7188D01*
X1337589Y8428D01*
Y2228D01*
G01X1350506Y17728D02*
X1350297Y17418D01*
X1349881D01*
X1349672Y17728D01*
X1349881Y18038D01*
X1350297D01*
X1350506Y17728D01*
G01X1350089Y29818D02*
X1347381Y30128D01*
X1345089Y30593D01*
X1343006Y31213D01*
X1340714Y31988D01*
X1337589Y33228D01*
Y27028D01*
G01X1350089Y42528D02*
X1349881Y43613D01*
X1349256Y44853D01*
X1348214Y45628D01*
X1346756Y45938D01*
X1345298Y45628D01*
X1344047Y44698D01*
X1343422Y43303D01*
Y41753D01*
X1343006Y40823D01*
X1341964Y40048D01*
X1340506Y39738D01*
X1339047Y40203D01*
X1338006Y41288D01*
X1337589Y42528D01*
X1338006Y43768D01*
X1339047Y44853D01*
X1340506Y45318D01*
X1341964Y45008D01*
X1343006Y44233D01*
X1343422Y43303D01*
Y41753D01*
X1344047Y40358D01*
X1345298Y39428D01*
X1346756Y39118D01*
X1348214Y39428D01*
X1349256Y40203D01*
X1349881Y41443D01*
X1350089Y42528D01*
G01X1489576Y-349434D02*
X1733985D01*
Y-633449D01*
X1489576D01*
Y-349434D01*
G01X1545088Y-574087D02*
X1554536D01*
G02Y-581961I0J-3937D01*
G01X1545088D01*
G01X1536820Y-500859D02*
G03I-5906J0D01*
G01X1536613Y-402356D02*
G03I-6250J0D01*
G01X1574221Y-574087D02*
G03Y-581961I0J-3937D01*
G01X1583670D01*
G01X1574221Y-574087D02*
X1583670D01*
M02*
